FILE_TYPE = MACRO_DRAWING;
SET COLOR_WIRE YELLOW;
SET COLOR_PROP MONO;
SET COLOR_DOT WHITE;
SET COLOR_ARC YELLOW;
SET COLOR_BODY GREEN;
SET COLOR_NOTE MONO;
SET PROP_DISPLAY VALUE;
SET PAGE_NUMBER P145;
FORCEADD RES..1
(-4750 -250);
FORCEPROP 1 LAST PACK_TYPE 0402
J 0
(-4500 -400);
DISPLAY 0.617021 (-4500 -400);
PAINT SKYBLUE (-4500 -400);
FORCEPROP 1 LAST MATERIAL EMPTY
J 0
(-4750 -400);
DISPLAY 0.617021 (-4750 -400);
PAINT RED (-4750 -400);
FORCEPROP 1 LAST PART_NUMBER G21497-005
J 0
(-4625 -225);
DISPLAY 0.617021 (-4625 -225);
PAINT BLUE (-4625 -225);
FORCEPROP 1 LAST TOLERANCE 5%
J 0
(-4650 -350);
DISPLAY 0.617021 (-4650 -350);
PAINT SKYBLUE (-4650 -350);
FORCEPROP 1 LASTPIN (-4650 -250) $PN 2
J 0
(-4688 -238);
DISPLAY 0.617021 (-4688 -238);
PAINT ORANGE (-4688 -238);
FORCEPROP 1 LAST LOCATION R9F60
J 0
(-4800 -150);
DISPLAY 0.617021 (-4800 -150);
PAINT AQUA (-4800 -150);
FORCEPROP 1 LASTPIN (-4850 -250) $PN 1
J 0
(-4838 -238);
DISPLAY 0.617021 (-4838 -238);
PAINT ORANGE (-4838 -238);
FORCEPROP 1 LAST VALUE 0.0
J 2
(-4825 -350);
DISPLAY 0.617021 (-4825 -350);
PAINT SKYBLUE (-4825 -350);
FORCEPROP 1 LAST WATTAGE 1/16W
J 2
(-4775 -400);
DISPLAY 0.617021 (-4775 -400);
PAINT SKYBLUE (-4775 -400);
FORCEPROP 0 LAST CDS_SEC 1
J 0
(-4800 -100);
PAINT MONO (-4800 -100);
DISPLAY INVISIBLE (-4800 -100);
FORCEPROP 0 LAST CDS_LOCATION R9F60
J 0
(-4800 -100);
PAINT MONO (-4800 -100);
DISPLAY INVISIBLE (-4800 -100);
FORCEPROP 0 LAST BOM_COST SM_CONTROLLER
J 0
(-4800 50);
DISPLAY 1.021277 (-4800 50);
PAINT ORANGE (-4800 50);
DISPLAY INVISIBLE (-4800 50);
FORCEPROP 2 LAST SEC 1
J 0
(-4800 -50);
DISPLAY 0.680851 (-4800 -50);
PAINT MONO (-4800 -50);
DISPLAY INVISIBLE (-4800 -50);
FORCEPROP 2 LAST SEC_TYPE 0402
J 0
(-4800 -50);
DISPLAY 1.021277 (-4800 -50);
PAINT ORANGE (-4800 -50);
DISPLAY INVISIBLE (-4800 -50);
FORCEPROP 0 LAST ROOM BMC
J 0
(-4800 -50);
DISPLAY 1.021277 (-4800 -50);
PAINT ORANGE (-4800 -50);
DISPLAY INVISIBLE (-4800 -50);
FORCEPROP 2 LAST CDS_LIB mstr_discrete
J 0
(-4750 -250);
PAINT ORANGE (-4750 -250);
DISPLAY INVISIBLE (-4750 -250);
FORCEPROP 1 LAST PATH I10
J 0
(-4800 -100);
DISPLAY 0.978723 (-4800 -100);
PAINT WHITE (-4800 -100);
DISPLAY INVISIBLE (-4800 -100);
FORCEADD RES..1
(-7450 -2400);
FORCEPROP 1 LAST VALUE 0.0
J 2
(-7550 -2450);
DISPLAY 0.617021 (-7550 -2450);
PAINT SKYBLUE (-7550 -2450);
FORCEPROP 1 LAST MATERIAL EMPTY
J 0
(-7550 -2350);
DISPLAY 0.617021 (-7550 -2350);
PAINT RED (-7550 -2350);
FORCEPROP 1 LAST PACK_TYPE 0402
J 0
(-7075 -2450);
DISPLAY 0.617021 (-7075 -2450);
PAINT SKYBLUE (-7075 -2450);
FORCEPROP 1 LAST LOCATION R1T15
J 0
(-7350 -2350);
DISPLAY 0.617021 (-7350 -2350);
PAINT AQUA (-7350 -2350);
FORCEPROP 1 LAST TOLERANCE 5%
J 0
(-7325 -2450);
DISPLAY 0.617021 (-7325 -2450);
PAINT SKYBLUE (-7325 -2450);
FORCEPROP 1 LAST WATTAGE 1/16W
J 2
(-7100 -2450);
DISPLAY 0.617021 (-7100 -2450);
PAINT SKYBLUE (-7100 -2450);
FORCEPROP 1 LAST PART_NUMBER G21497-005
J 0
(-7375 -2525);
DISPLAY 0.617021 (-7375 -2525);
PAINT BLUE (-7375 -2525);
FORCEPROP 1 LASTPIN (-7350 -2400) $PN 2
J 0
(-7388 -2388);
DISPLAY 0.787234 (-7388 -2388);
PAINT ORANGE (-7388 -2388);
DISPLAY INVISIBLE (-7388 -2388);
FORCEPROP 1 LASTPIN (-7550 -2400) $PN 1
J 0
(-7538 -2388);
DISPLAY 0.787234 (-7538 -2388);
PAINT ORANGE (-7538 -2388);
DISPLAY INVISIBLE (-7538 -2388);
FORCEPROP 2 LAST CDS_LIB mstr_discrete
J 0
(-7450 -2400);
PAINT MONO (-7450 -2400);
DISPLAY INVISIBLE (-7450 -2400);
FORCEPROP 1 LAST PATH I100
J 0
(-7500 -2250);
DISPLAY 0.978723 (-7500 -2250);
PAINT WHITE (-7500 -2250);
DISPLAY INVISIBLE (-7500 -2250);
FORCEADD RES..1
R 5
(-7000 -2650);
FORCEPROP 1 LAST PART_NUMBER G21497-005
R 3
J 0
(-7125 -2725);
DISPLAY 0.617021 (-7125 -2725);
PAINT BLUE (-7125 -2725);
FORCEPROP 1 LAST WATTAGE 1/16W
R 3
J 2
(-7050 -3000);
DISPLAY 0.617021 (-7050 -3000);
PAINT SKYBLUE (-7050 -3000);
FORCEPROP 1 LAST LOCATION R1T23
R 3
J 0
(-6950 -2750);
DISPLAY 0.617021 (-6950 -2750);
PAINT AQUA (-6950 -2750);
FORCEPROP 1 LAST MATERIAL EMPTY
R 3
J 0
(-6950 -2550);
DISPLAY 0.617021 (-6950 -2550);
PAINT RED (-6950 -2550);
FORCEPROP 1 LAST VALUE 0.0
R 3
J 2
(-7050 -2550);
DISPLAY 0.617021 (-7050 -2550);
PAINT SKYBLUE (-7050 -2550);
FORCEPROP 1 LAST PACK_TYPE 0402
R 3
J 0
(-7050 -3025);
DISPLAY 0.617021 (-7050 -3025);
PAINT SKYBLUE (-7050 -3025);
FORCEPROP 1 LAST TOLERANCE 5%
R 3
J 0
(-7050 -2775);
DISPLAY 0.617021 (-7050 -2775);
PAINT SKYBLUE (-7050 -2775);
FORCEPROP 1 LASTPIN (-7000 -2750) $PN 2
R 3
J 0
(-6988 -2712);
DISPLAY 0.787234 (-6988 -2712);
PAINT ORANGE (-6988 -2712);
DISPLAY INVISIBLE (-6988 -2712);
FORCEPROP 1 LASTPIN (-7000 -2550) $PN 1
R 3
J 0
(-6988 -2562);
DISPLAY 0.787234 (-6988 -2562);
PAINT ORANGE (-6988 -2562);
DISPLAY INVISIBLE (-6988 -2562);
FORCEPROP 2 LAST CDS_LIB mstr_discrete
R 3
J 0
(-7000 -2650);
PAINT MONO (-7000 -2650);
DISPLAY INVISIBLE (-7000 -2650);
FORCEPROP 1 LAST PATH I101
R 3
J 0
(-6850 -2600);
DISPLAY 0.978723 (-6850 -2600);
PAINT WHITE (-6850 -2600);
DISPLAY INVISIBLE (-6850 -2600);
FORCEADD GND..1
(-7000 -3175);
FORCEPROP 3 LASTPIN (-7000 -3125) SIG_NAME GND\g
J 0
(-6990 -3115);
DISPLAY 0.659574 (-6990 -3115);
PAINT MONO (-6990 -3115);
DISPLAY INVISIBLE (-6990 -3115);
FORCEPROP 1 LAST HDL_POWER GND
J 0
(-7000 -3025);
DISPLAY 0.872340 (-7000 -3025);
PAINT GREEN (-7000 -3025);
DISPLAY INVISIBLE (-7000 -3025);
FORCEPROP 1 LAST BODY_TYPE PLUMBING
J 0
(-7045 -3218);
DISPLAY 0.340426 (-7045 -3218);
PAINT GREEN (-7045 -3218);
DISPLAY INVISIBLE (-7045 -3218);
FORCEPROP 1 LAST SIZE 1B
J 0
(-6925 -3225);
DISPLAY 0.872340 (-6925 -3225);
PAINT AQUA (-6925 -3225);
DISPLAY INVISIBLE (-6925 -3225);
FORCEPROP 1 LAST VOLTAGE 0.0V
J 0
(-7045 -3218);
DISPLAY 0.340426 (-7045 -3218);
PAINT GREEN (-7045 -3218);
DISPLAY INVISIBLE (-7045 -3218);
FORCEPROP 1 LAST PATH I102
J 0
(-6925 -3175);
DISPLAY 0.872340 (-6925 -3175);
PAINT AQUA (-6925 -3175);
DISPLAY INVISIBLE (-6925 -3175);
FORCEPROP 2 LAST CDS_LIB mstr_symbols
J 0
(-7000 -3175);
PAINT MONO (-7000 -3175);
DISPLAY INVISIBLE (-7000 -3175);
FORCEADD OFFPAGE..3
(-6550 -2400);
FORCEPROP 2 LAST $XR0 145 
J 0
(-6126 -2400);
DISPLAY 0.638298 (-6126 -2400);
PAINT MONO (-6126 -2400);
FORCEPROP 1 LAST COMMENT_BODY TRUE
J 0
(-6600 -2500);
DISPLAY 0.872340 (-6600 -2500);
PAINT GREEN (-6600 -2500);
DISPLAY INVISIBLE (-6600 -2500);
FORCEPROP 1 LAST OFFPAGE TRUE
J 0
(-6225 -2525);
DISPLAY 0.872340 (-6225 -2525);
PAINT GREEN (-6225 -2525);
DISPLAY INVISIBLE (-6225 -2525);
FORCEPROP 2 LAST PATH I103
J 0
(-6350 -2325);
DISPLAY 1.021277 (-6350 -2325);
PAINT ORANGE (-6350 -2325);
DISPLAY INVISIBLE (-6350 -2325);
FORCEPROP 2 LAST CDS_LIB mstr_standard
J 0
(-6550 -2400);
PAINT MONO (-6550 -2400);
DISPLAY INVISIBLE (-6550 -2400);
FORCEADD OFFPAGE..5
(-8000 -2400);
FORCEPROP 2 LAST $XR0 191 
J 0
(-8429 -2400);
DISPLAY 0.638298 (-8429 -2400);
PAINT MONO (-8429 -2400);
DISPLAY INVISIBLE (-8429 -2400);
FORCEPROP 1 LAST COMMENT_BODY TRUE
J 0
(-7900 -2475);
DISPLAY 0.872340 (-7900 -2475);
PAINT GREEN (-7900 -2475);
DISPLAY INVISIBLE (-7900 -2475);
FORCEPROP 1 LAST OFFPAGE TRUE
J 0
(-7675 -2525);
DISPLAY 0.872340 (-7675 -2525);
PAINT GREEN (-7675 -2525);
DISPLAY INVISIBLE (-7675 -2525);
FORCEPROP 2 LAST PATH I104
J 0
(-7950 -2325);
DISPLAY 1.021277 (-7950 -2325);
PAINT ORANGE (-7950 -2325);
DISPLAY INVISIBLE (-7950 -2325);
FORCEPROP 2 LAST CDS_LIB mstr_standard
J 0
(-8000 -2400);
PAINT MONO (-8000 -2400);
DISPLAY INVISIBLE (-8000 -2400);
FORCEADD OFFPAGE..6
(-6125 -1850);
FORCEPROP 2 LAST $XRERR ?
J 0
(-6549 -1850);
DISPLAY 0.638298 (-6549 -1850);
PAINT MONO (-6549 -1850);
DISPLAY INVISIBLE (-6549 -1850);
FORCEPROP 1 LAST COMMENT_BODY TRUE
J 0
(-6025 -1925);
DISPLAY 0.872340 (-6025 -1925);
PAINT GREEN (-6025 -1925);
DISPLAY INVISIBLE (-6025 -1925);
FORCEPROP 1 LAST OFFPAGE TRUE
J 0
(-5800 -1975);
DISPLAY 0.872340 (-5800 -1975);
PAINT GREEN (-5800 -1975);
DISPLAY INVISIBLE (-5800 -1975);
FORCEPROP 2 LAST PATH I109
J 0
(-6075 -1775);
DISPLAY 1.021277 (-6075 -1775);
PAINT ORANGE (-6075 -1775);
DISPLAY INVISIBLE (-6075 -1775);
FORCEPROP 2 LAST CDS_LIB mstr_standard
J 0
(-6125 -1850);
PAINT MONO (-6125 -1850);
DISPLAY INVISIBLE (-6125 -1850);
FORCEPROP 2 LAST $XRERR ?
J 0
(-6549 -1850);
DISPLAY 0.638298 (-6549 -1850);
PAINT MONO (-6549 -1850);
DISPLAY INVISIBLE (-6549 -1850);
FORCEPROP 2 LAST $XRERR UNIQUE?
J 0
(-6549 -1850);
DISPLAY 0.638298 (-6549 -1850);
PAINT MONO (-6549 -1850);
DISPLAY INVISIBLE (-6549 -1850);
FORCEADD RES..1
(-4750 -550);
FORCEPROP 1 LAST WATTAGE 1/16W
J 2
(-4775 -700);
DISPLAY 0.617021 (-4775 -700);
PAINT SKYBLUE (-4775 -700);
FORCEPROP 1 LAST MATERIAL CHIP
J 0
(-4750 -700);
DISPLAY 0.617021 (-4750 -700);
PAINT SKYBLUE (-4750 -700);
FORCEPROP 1 LAST PACK_TYPE 0402
J 0
(-4500 -700);
DISPLAY 0.617021 (-4500 -700);
PAINT SKYBLUE (-4500 -700);
FORCEPROP 1 LAST PART_NUMBER G21497-005
J 0
(-4800 -450);
DISPLAY 0.617021 (-4800 -450);
PAINT BLUE (-4800 -450);
FORCEPROP 1 LAST LOCATION R9F62
J 0
(-4800 -500);
DISPLAY 0.617021 (-4800 -500);
PAINT AQUA (-4800 -500);
FORCEPROP 1 LASTPIN (-4650 -550) $PN 2
J 0
(-4688 -538);
DISPLAY 0.617021 (-4688 -538);
PAINT ORANGE (-4688 -538);
FORCEPROP 1 LAST TOLERANCE 5%
J 0
(-4750 -650);
DISPLAY 0.617021 (-4750 -650);
PAINT SKYBLUE (-4750 -650);
FORCEPROP 1 LASTPIN (-4850 -550) $PN 1
J 0
(-4838 -538);
DISPLAY 0.617021 (-4838 -538);
PAINT ORANGE (-4838 -538);
FORCEPROP 1 LAST VALUE 0.0
J 2
(-4775 -650);
DISPLAY 0.617021 (-4775 -650);
PAINT SKYBLUE (-4775 -650);
FORCEPROP 0 LAST CDS_SEC 1
J 0
(-4800 -400);
PAINT MONO (-4800 -400);
DISPLAY INVISIBLE (-4800 -400);
FORCEPROP 0 LAST CDS_LOCATION R9F62
J 0
(-4800 -400);
PAINT MONO (-4800 -400);
DISPLAY INVISIBLE (-4800 -400);
FORCEPROP 0 LAST BOM_COST SM_CONTROLLER
J 0
(-4800 -250);
DISPLAY 1.021277 (-4800 -250);
PAINT ORANGE (-4800 -250);
DISPLAY INVISIBLE (-4800 -250);
FORCEPROP 0 LAST ROOM BMC
J 0
(-4800 -350);
DISPLAY 1.021277 (-4800 -350);
PAINT ORANGE (-4800 -350);
DISPLAY INVISIBLE (-4800 -350);
FORCEPROP 2 LAST SEC_TYPE 0402
J 0
(-4800 -350);
DISPLAY 1.021277 (-4800 -350);
PAINT ORANGE (-4800 -350);
DISPLAY INVISIBLE (-4800 -350);
FORCEPROP 2 LAST SEC 1
J 0
(-4800 -350);
DISPLAY 0.680851 (-4800 -350);
PAINT MONO (-4800 -350);
DISPLAY INVISIBLE (-4800 -350);
FORCEPROP 2 LAST CDS_LIB mstr_discrete
J 0
(-4750 -550);
PAINT ORANGE (-4750 -550);
DISPLAY INVISIBLE (-4750 -550);
FORCEPROP 1 LAST PATH I11
J 0
(-4800 -400);
DISPLAY 0.978723 (-4800 -400);
PAINT WHITE (-4800 -400);
DISPLAY INVISIBLE (-4800 -400);
FORCEADD OFFPAGE..5
(-6150 -1900);
FORCEPROP 2 LAST $XRERR ?
J 0
(-6549 -1900);
DISPLAY 0.638298 (-6549 -1900);
PAINT MONO (-6549 -1900);
DISPLAY INVISIBLE (-6549 -1900);
FORCEPROP 1 LAST COMMENT_BODY TRUE
J 0
(-6050 -1975);
DISPLAY 0.872340 (-6050 -1975);
PAINT GREEN (-6050 -1975);
DISPLAY INVISIBLE (-6050 -1975);
FORCEPROP 1 LAST OFFPAGE TRUE
J 0
(-5825 -2025);
DISPLAY 0.872340 (-5825 -2025);
PAINT GREEN (-5825 -2025);
DISPLAY INVISIBLE (-5825 -2025);
FORCEPROP 2 LAST PATH I110
J 0
(-6100 -1825);
DISPLAY 1.021277 (-6100 -1825);
PAINT ORANGE (-6100 -1825);
DISPLAY INVISIBLE (-6100 -1825);
FORCEPROP 2 LAST CDS_LIB mstr_standard
J 0
(-6150 -1900);
PAINT MONO (-6150 -1900);
DISPLAY INVISIBLE (-6150 -1900);
FORCEPROP 2 LAST $XRERR ?
J 0
(-6549 -1900);
DISPLAY 0.638298 (-6549 -1900);
PAINT MONO (-6549 -1900);
DISPLAY INVISIBLE (-6549 -1900);
FORCEPROP 2 LAST $XRERR UNIQUE?
J 0
(-6549 -1900);
DISPLAY 0.638298 (-6549 -1900);
PAINT MONO (-6549 -1900);
DISPLAY INVISIBLE (-6549 -1900);
FORCEADD OFFPAGE..6
(-6125 -2300);
FORCEPROP 2 LAST $XRERR ?
J 0
(-6549 -2300);
DISPLAY 0.638298 (-6549 -2300);
PAINT MONO (-6549 -2300);
DISPLAY INVISIBLE (-6549 -2300);
FORCEPROP 1 LAST COMMENT_BODY TRUE
J 0
(-6025 -2375);
DISPLAY 0.872340 (-6025 -2375);
PAINT GREEN (-6025 -2375);
DISPLAY INVISIBLE (-6025 -2375);
FORCEPROP 1 LAST OFFPAGE TRUE
J 0
(-5800 -2425);
DISPLAY 0.872340 (-5800 -2425);
PAINT GREEN (-5800 -2425);
DISPLAY INVISIBLE (-5800 -2425);
FORCEPROP 2 LAST PATH I111
J 0
(-6075 -2225);
DISPLAY 1.021277 (-6075 -2225);
PAINT ORANGE (-6075 -2225);
DISPLAY INVISIBLE (-6075 -2225);
FORCEPROP 2 LAST CDS_LIB mstr_standard
J 0
(-6125 -2300);
PAINT MONO (-6125 -2300);
DISPLAY INVISIBLE (-6125 -2300);
FORCEPROP 2 LAST $XRERR ?
J 0
(-6549 -2300);
DISPLAY 0.638298 (-6549 -2300);
PAINT MONO (-6549 -2300);
DISPLAY INVISIBLE (-6549 -2300);
FORCEPROP 2 LAST $XRERR UNIQUE?
J 0
(-6549 -2300);
DISPLAY 0.638298 (-6549 -2300);
PAINT MONO (-6549 -2300);
DISPLAY INVISIBLE (-6549 -2300);
FORCEADD OFFPAGE..5
(-6150 -2350);
FORCEPROP 2 LAST $XRERR ?
J 0
(-6549 -2350);
DISPLAY 0.638298 (-6549 -2350);
PAINT MONO (-6549 -2350);
DISPLAY INVISIBLE (-6549 -2350);
FORCEPROP 1 LAST COMMENT_BODY TRUE
J 0
(-6050 -2425);
DISPLAY 0.872340 (-6050 -2425);
PAINT GREEN (-6050 -2425);
DISPLAY INVISIBLE (-6050 -2425);
FORCEPROP 1 LAST OFFPAGE TRUE
J 0
(-5825 -2475);
DISPLAY 0.872340 (-5825 -2475);
PAINT GREEN (-5825 -2475);
DISPLAY INVISIBLE (-5825 -2475);
FORCEPROP 2 LAST PATH I112
J 0
(-6100 -2275);
DISPLAY 1.021277 (-6100 -2275);
PAINT ORANGE (-6100 -2275);
DISPLAY INVISIBLE (-6100 -2275);
FORCEPROP 2 LAST CDS_LIB mstr_standard
J 0
(-6150 -2350);
PAINT MONO (-6150 -2350);
DISPLAY INVISIBLE (-6150 -2350);
FORCEPROP 2 LAST $XRERR ?
J 0
(-6549 -2350);
DISPLAY 0.638298 (-6549 -2350);
PAINT MONO (-6549 -2350);
DISPLAY INVISIBLE (-6549 -2350);
FORCEPROP 2 LAST $XRERR UNIQUE?
J 0
(-6549 -2350);
DISPLAY 0.638298 (-6549 -2350);
PAINT MONO (-6549 -2350);
DISPLAY INVISIBLE (-6549 -2350);
FORCEADD OFFPAGE..5
(-6175 -2050);
FORCEPROP 2 LAST $XR0 160 
J 0
(-6430 -2050);
DISPLAY 0.638298 (-6430 -2050);
PAINT MONO (-6430 -2050);
FORCEPROP 1 LAST COMMENT_BODY TRUE
J 0
(-6075 -2125);
DISPLAY 0.872340 (-6075 -2125);
PAINT GREEN (-6075 -2125);
DISPLAY INVISIBLE (-6075 -2125);
FORCEPROP 1 LAST OFFPAGE TRUE
J 0
(-5850 -2175);
DISPLAY 0.872340 (-5850 -2175);
PAINT GREEN (-5850 -2175);
DISPLAY INVISIBLE (-5850 -2175);
FORCEPROP 2 LAST CDS_LIB mstr_standard
J 0
(-6175 -2050);
PAINT MONO (-6175 -2050);
DISPLAY INVISIBLE (-6175 -2050);
FORCEPROP 2 LAST PATH I115
J 0
(-6125 -1975);
DISPLAY 1.021277 (-6125 -1975);
PAINT ORANGE (-6125 -1975);
DISPLAY INVISIBLE (-6125 -1975);
FORCEADD OFFPAGE..3
R 2
(-6150 -2000);
FORCEPROP 2 LAST $XR0 160 
J 0
(-6430 -2000);
DISPLAY 0.638298 (-6430 -2000);
PAINT MONO (-6430 -2000);
FORCEPROP 1 LAST COMMENT_BODY TRUE
J 2
(-6100 -2100);
DISPLAY 1.170213 (-6100 -2100);
PAINT GREEN (-6100 -2100);
DISPLAY INVISIBLE (-6100 -2100);
FORCEPROP 1 LAST OFFPAGE TRUE
J 2
(-6475 -2125);
PAINT GREEN (-6475 -2125);
DISPLAY INVISIBLE (-6475 -2125);
FORCEPROP 2 LAST ROOM BMC
J 2
(-6625 -1950);
PAINT MONO (-6625 -1950);
DISPLAY INVISIBLE (-6625 -1950);
FORCEPROP 2 LAST BOM_COST SM_CONTROLLER
J 2
(-6625 -1950);
PAINT MONO (-6625 -1950);
DISPLAY INVISIBLE (-6625 -1950);
FORCEPROP 2 LAST CDS_LIB mstr_standard
J 0
(-6150 -2000);
PAINT MONO (-6150 -2000);
DISPLAY INVISIBLE (-6150 -2000);
FORCEPROP 2 LAST PATH I116
J 0
(-6100 -1925);
DISPLAY 1.021277 (-6100 -1925);
PAINT ORANGE (-6100 -1925);
DISPLAY INVISIBLE (-6100 -1925);
FORCEADD AST2520A1-GP-GP..3
(-3800 -2550);
FORCEPROP 1 LAST VALUE AST2520A1-GP-GP
J 0
(-4950 -4000);
DISPLAY 0.617021 (-4950 -4000);
PAINT GREEN (-4950 -4000);
FORCEPROP 1 LAST LOCATION U25W4
J 0
(-4950 -1125);
DISPLAY 0.617021 (-4950 -1125);
PAINT GREEN (-4950 -1125);
FORCEPROP 2 LAST CDS_LIB w_hdl
J 0
(-3800 -2550);
PAINT MONO (-3800 -2550);
DISPLAY INVISIBLE (-3800 -2550);
FORCEPROP 1 LAST CDS_LMAN_SYM_OUTLINE -1150,1400,1150,-1400
J 0
(-3800 -2550);
DISPLAY 0.468085 (-3800 -2550);
PAINT GREEN (-3800 -2550);
DISPLAY INVISIBLE (-3800 -2550);
FORCEPROP 1 LAST PATH I117
J 0
(-3800 -2550);
DISPLAY 0.617021 (-3800 -2550);
PAINT GREEN (-3800 -2550);
DISPLAY INVISIBLE (-3800 -2550);
FORCEPROP 1 LAST PART_NUMBER 071.2520A.M001
J 0
(-3800 -2550);
DISPLAY 0.617021 (-3800 -2550);
PAINT GREEN (-3800 -2550);
DISPLAY INVISIBLE (-3800 -2550);
FORCEPROP 1 LAST PACK_TYPE ASIC2-GB1
J 0
(-3800 -2550);
DISPLAY 0.617021 (-3800 -2550);
PAINT GREEN (-3800 -2550);
DISPLAY INVISIBLE (-3800 -2550);
FORCEADD OFFPAGE..1
(-5400 -250);
FORCEPROP 2 LAST $XR0 101 
J 0
(-5652 -250);
DISPLAY 0.638298 (-5652 -250);
PAINT MONO (-5652 -250);
FORCEPROP 1 LAST COMMENT_BODY TRUE
J 0
(-5275 -350);
DISPLAY 0.872340 (-5275 -350);
PAINT GREEN (-5275 -350);
DISPLAY INVISIBLE (-5275 -350);
FORCEPROP 1 LAST OFFPAGE TRUE
J 0
(-5075 -375);
DISPLAY 0.872340 (-5075 -375);
PAINT GREEN (-5075 -375);
DISPLAY INVISIBLE (-5075 -375);
FORCEPROP 2 LAST CDS_LIB mstr_standard
J 0
(-5400 -250);
PAINT ORANGE (-5400 -250);
DISPLAY INVISIBLE (-5400 -250);
FORCEPROP 2 LAST PATH I12
J 0
(-5650 -200);
DISPLAY 1.021277 (-5650 -200);
PAINT ORANGE (-5650 -200);
DISPLAY INVISIBLE (-5650 -200);
FORCEADD GND..1
(-5575 -875);
FORCEPROP 3 LASTPIN (-5575 -825) SIG_NAME GND\g
J 0
(-5565 -815);
DISPLAY 0.659574 (-5565 -815);
PAINT MONO (-5565 -815);
DISPLAY INVISIBLE (-5565 -815);
FORCEPROP 1 LAST HDL_POWER GND
J 0
(-5575 -725);
DISPLAY 0.872340 (-5575 -725);
PAINT GREEN (-5575 -725);
DISPLAY INVISIBLE (-5575 -725);
FORCEPROP 1 LAST BODY_TYPE PLUMBING
J 0
(-5620 -918);
DISPLAY 0.340426 (-5620 -918);
PAINT GREEN (-5620 -918);
DISPLAY INVISIBLE (-5620 -918);
FORCEPROP 1 LAST VOLTAGE 0.0V
J 0
(-5620 -918);
DISPLAY 0.340426 (-5620 -918);
PAINT SKYBLUE (-5620 -918);
DISPLAY INVISIBLE (-5620 -918);
FORCEPROP 1 LAST SIZE 1B
J 0
(-5500 -925);
DISPLAY 0.872340 (-5500 -925);
PAINT AQUA (-5500 -925);
DISPLAY INVISIBLE (-5500 -925);
FORCEPROP 2 LAST CDS_LIB mstr_symbols
J 0
(-5575 -875);
PAINT ORANGE (-5575 -875);
DISPLAY INVISIBLE (-5575 -875);
FORCEPROP 1 LAST PATH I13
J 0
(-5500 -875);
DISPLAY 0.872340 (-5500 -875);
PAINT AQUA (-5500 -875);
DISPLAY INVISIBLE (-5500 -875);
FORCEADD RES..2
(-7000 -475);
FORCEPROP 1 LAST LOCATION R9F61
J 0
(-6955 -350);
DISPLAY 0.617021 (-6955 -350);
PAINT AQUA (-6955 -350);
FORCEPROP 1 LAST VALUE 10.0K
J 0
(-6955 -400);
DISPLAY 0.617021 (-6955 -400);
PAINT SKYBLUE (-6955 -400);
FORCEPROP 1 LAST TOLERANCE 1%
J 0
(-6955 -450);
DISPLAY 0.617021 (-6955 -450);
PAINT SKYBLUE (-6955 -450);
FORCEPROP 1 LAST WATTAGE 1/16W
J 0
(-6960 -500);
DISPLAY 0.617021 (-6960 -500);
PAINT SKYBLUE (-6960 -500);
FORCEPROP 1 LASTPIN (-7000 -375) $PN 1
J 0
(-6995 -413);
DISPLAY 0.617021 (-6995 -413);
PAINT ORANGE (-6995 -413);
FORCEPROP 1 LAST PACK_TYPE 0402
J 0
(-6960 -650);
DISPLAY 0.617021 (-6960 -650);
PAINT SKYBLUE (-6960 -650);
FORCEPROP 1 LAST PART_NUMBER G21796-016
J 0
(-6960 -600);
DISPLAY 0.617021 (-6960 -600);
PAINT BLUE (-6960 -600);
FORCEPROP 1 LAST MATERIAL CHIP
J 0
(-6960 -550);
DISPLAY 0.617021 (-6960 -550);
PAINT SKYBLUE (-6960 -550);
FORCEPROP 1 LASTPIN (-7000 -575) $PN 2
J 0
(-6995 -565);
DISPLAY 0.617021 (-6995 -565);
PAINT ORANGE (-6995 -565);
FORCEPROP 0 LAST CDS_SEC 1
J 0
(-6950 -300);
PAINT MONO (-6950 -300);
DISPLAY INVISIBLE (-6950 -300);
FORCEPROP 0 LAST CDS_LOCATION R9F61
J 0
(-6950 -300);
PAINT MONO (-6950 -300);
DISPLAY INVISIBLE (-6950 -300);
FORCEPROP 2 LAST SEC 1
J 0
(-6950 -250);
DISPLAY 0.680851 (-6950 -250);
PAINT MONO (-6950 -250);
DISPLAY INVISIBLE (-6950 -250);
FORCEPROP 0 LAST BOM_COST SM_CONTROLLER
J 0
(-6950 -150);
DISPLAY 1.021277 (-6950 -150);
PAINT ORANGE (-6950 -150);
DISPLAY INVISIBLE (-6950 -150);
FORCEPROP 2 LAST SEC_TYPE 0402
J 0
(-6950 -250);
DISPLAY 1.021277 (-6950 -250);
PAINT ORANGE (-6950 -250);
DISPLAY INVISIBLE (-6950 -250);
FORCEPROP 0 LAST ROOM BMC
J 0
(-6950 -250);
DISPLAY 1.021277 (-6950 -250);
PAINT ORANGE (-6950 -250);
DISPLAY INVISIBLE (-6950 -250);
FORCEPROP 2 LAST CDS_LIB mstr_discrete
J 0
(-7000 -475);
PAINT ORANGE (-7000 -475);
DISPLAY INVISIBLE (-7000 -475);
FORCEPROP 1 LAST PATH I14
J 0
(-6950 -300);
DISPLAY 0.978723 (-6950 -300);
PAINT WHITE (-6950 -300);
DISPLAY INVISIBLE (-6950 -300);
FORCEADD CAP_A..1
(-7500 -450);
FORCEPROP 1 LAST LOCATION C9F23
J 0
(-7450 -350);
DISPLAY 0.617021 (-7450 -350);
PAINT AQUA (-7450 -350);
FORCEPROP 1 LAST VALUE 0.1UF
J 0
(-7450 -400);
DISPLAY 0.617021 (-7450 -400);
PAINT SKYBLUE (-7450 -400);
FORCEPROP 1 LAST PART_NUMBER A36096-030
J 0
(-7450 -600);
DISPLAY 0.617021 (-7450 -600);
PAINT BLUE (-7450 -600);
FORCEPROP 1 LAST MATERIAL X7R
J 0
(-7450 -550);
DISPLAY 0.617021 (-7450 -550);
PAINT SKYBLUE (-7450 -550);
FORCEPROP 1 LAST TOLERANCE 10%
J 0
(-7450 -500);
DISPLAY 0.617021 (-7450 -500);
PAINT SKYBLUE (-7450 -500);
FORCEPROP 1 LAST VOLTAGE 16V
J 0
(-7450 -450);
DISPLAY 0.617021 (-7450 -450);
PAINT SKYBLUE (-7450 -450);
FORCEPROP 1 LASTPIN (-7500 -350) $PN 1
J 0
(-7490 -370);
DISPLAY 0.617021 (-7490 -370);
PAINT ORANGE (-7490 -370);
FORCEPROP 1 LAST PACK_TYPE 0402V
J 0
(-7450 -650);
DISPLAY 0.617021 (-7450 -650);
PAINT SKYBLUE (-7450 -650);
FORCEPROP 1 LASTPIN (-7500 -550) $PN 2
J 0
(-7490 -570);
DISPLAY 0.617021 (-7490 -570);
PAINT ORANGE (-7490 -570);
FORCEPROP 0 LAST CDS_LOCATION C9F23
J 0
(-7450 -300);
PAINT MONO (-7450 -300);
DISPLAY INVISIBLE (-7450 -300);
FORCEPROP 0 LAST BOM_COST SM_CONTROLLER
J 0
(-7450 -150);
DISPLAY 1.021277 (-7450 -150);
PAINT ORANGE (-7450 -150);
DISPLAY INVISIBLE (-7450 -150);
FORCEPROP 2 LAST SEC_TYPE 0402V
J 0
(-7450 -250);
DISPLAY 1.021277 (-7450 -250);
PAINT ORANGE (-7450 -250);
DISPLAY INVISIBLE (-7450 -250);
FORCEPROP 0 LAST ROOM BMC
J 0
(-7450 -250);
DISPLAY 1.021277 (-7450 -250);
PAINT ORANGE (-7450 -250);
DISPLAY INVISIBLE (-7450 -250);
FORCEPROP 2 LAST CDS_SEC 1
J 0
(-7450 -300);
PAINT ORANGE (-7450 -300);
DISPLAY INVISIBLE (-7450 -300);
FORCEPROP 2 LAST SEC 1
J 0
(-7450 -300);
DISPLAY 0.680851 (-7450 -300);
PAINT MONO (-7450 -300);
DISPLAY INVISIBLE (-7450 -300);
FORCEPROP 2 LAST CDS_LIB dev_discrete
J 0
(-7500 -450);
PAINT ORANGE (-7500 -450);
DISPLAY INVISIBLE (-7500 -450);
FORCEPROP 1 LAST PATH I15
J 0
(-7450 -300);
DISPLAY 0.978723 (-7450 -300);
PAINT WHITE (-7450 -300);
DISPLAY INVISIBLE (-7450 -300);
FORCEADD P3V3_STBY..1
(-7500 -200);
FORCEPROP 3 LASTPIN (-7500 -250) SIG_NAME P3V3_STBY\g
J 0
(-7490 -240);
DISPLAY 0.659574 (-7490 -240);
PAINT MONO (-7490 -240);
DISPLAY INVISIBLE (-7490 -240);
FORCEPROP 1 LAST HDL_POWER P3V3_STBY
J 0
(-7800 -325);
DISPLAY 0.872340 (-7800 -325);
PAINT ORANGE (-7800 -325);
DISPLAY INVISIBLE (-7800 -325);
FORCEPROP 1 LAST BODY_TYPE PLUMBING
J 0
(-7545 -243);
DISPLAY 0.340426 (-7545 -243);
PAINT GREEN (-7545 -243);
DISPLAY INVISIBLE (-7545 -243);
FORCEPROP 1 LAST VOLTAGE 3.3V
J 0
(-7545 -243);
DISPLAY 0.340426 (-7545 -243);
PAINT SKYBLUE (-7545 -243);
DISPLAY INVISIBLE (-7545 -243);
FORCEPROP 2 LAST CDS_LIB mstr_symbols
J 0
(-7500 -200);
PAINT ORANGE (-7500 -200);
DISPLAY INVISIBLE (-7500 -200);
FORCEPROP 1 LAST SIZE 1B
J 0
(-7455 -178);
DISPLAY 0.340426 (-7455 -178);
PAINT GREEN (-7455 -178);
DISPLAY INVISIBLE (-7455 -178);
FORCEPROP 1 LAST PATH I16
J 0
(-7455 -198);
DISPLAY 0.340426 (-7455 -198);
PAINT GREEN (-7455 -198);
DISPLAY INVISIBLE (-7455 -198);
FORCEADD GND..1
(-7500 -675);
FORCEPROP 3 LASTPIN (-7500 -625) SIG_NAME GND\g
J 0
(-7490 -615);
DISPLAY 0.659574 (-7490 -615);
PAINT MONO (-7490 -615);
DISPLAY INVISIBLE (-7490 -615);
FORCEPROP 1 LAST HDL_POWER GND
J 0
(-7500 -525);
DISPLAY 0.872340 (-7500 -525);
PAINT GREEN (-7500 -525);
DISPLAY INVISIBLE (-7500 -525);
FORCEPROP 1 LAST BODY_TYPE PLUMBING
J 0
(-7545 -718);
DISPLAY 0.340426 (-7545 -718);
PAINT GREEN (-7545 -718);
DISPLAY INVISIBLE (-7545 -718);
FORCEPROP 2 LAST CDS_LIB mstr_symbols
J 0
(-7500 -675);
PAINT ORANGE (-7500 -675);
DISPLAY INVISIBLE (-7500 -675);
FORCEPROP 1 LAST VOLTAGE 0.0V
J 0
(-7545 -718);
DISPLAY 0.340426 (-7545 -718);
PAINT SKYBLUE (-7545 -718);
DISPLAY INVISIBLE (-7545 -718);
FORCEPROP 1 LAST SIZE 1B
J 0
(-7425 -725);
DISPLAY 0.872340 (-7425 -725);
PAINT AQUA (-7425 -725);
DISPLAY INVISIBLE (-7425 -725);
FORCEPROP 1 LAST PATH I17
J 0
(-7425 -675);
DISPLAY 0.872340 (-7425 -675);
PAINT AQUA (-7425 -675);
DISPLAY INVISIBLE (-7425 -675);
FORCEADD OFFPAGE..5
(-6000 -3150);
FORCEPROP 2 LAST $XR1 149 
J 0
(-6375 -3150);
DISPLAY 0.638298 (-6375 -3150);
PAINT MONO (-6375 -3150);
FORCEPROP 2 LAST $XR0 119 
J 0
(-6255 -3150);
DISPLAY 0.638298 (-6255 -3150);
PAINT MONO (-6255 -3150);
FORCEPROP 1 LAST COMMENT_BODY TRUE
J 0
(-5900 -3225);
DISPLAY 0.872340 (-5900 -3225);
PAINT GREEN (-5900 -3225);
DISPLAY INVISIBLE (-5900 -3225);
FORCEPROP 1 LAST OFFPAGE TRUE
J 0
(-5675 -3275);
DISPLAY 0.872340 (-5675 -3275);
PAINT GREEN (-5675 -3275);
DISPLAY INVISIBLE (-5675 -3275);
FORCEPROP 2 LAST CDS_LIB mstr_standard
J 0
(-6000 -3150);
PAINT MONO (-6000 -3150);
DISPLAY INVISIBLE (-6000 -3150);
FORCEPROP 2 LAST PATH I18
J 0
(-6250 -3100);
DISPLAY 1.021277 (-6250 -3100);
PAINT ORANGE (-6250 -3100);
DISPLAY INVISIBLE (-6250 -3100);
FORCEADD OFFPAGE..5
(-6000 -3000);
FORCEPROP 2 LAST $XR2 119 
J 0
(-6495 -3000);
DISPLAY 0.638298 (-6495 -3000);
PAINT MONO (-6495 -3000);
FORCEPROP 2 LAST $XR1 186 
J 0
(-6375 -3000);
DISPLAY 0.638298 (-6375 -3000);
PAINT MONO (-6375 -3000);
FORCEPROP 2 LAST $XR0 133 
J 0
(-6255 -3000);
DISPLAY 0.638298 (-6255 -3000);
PAINT MONO (-6255 -3000);
FORCEPROP 1 LAST COMMENT_BODY TRUE
J 0
(-5900 -3075);
DISPLAY 0.872340 (-5900 -3075);
PAINT GREEN (-5900 -3075);
DISPLAY INVISIBLE (-5900 -3075);
FORCEPROP 1 LAST OFFPAGE TRUE
J 0
(-5675 -3125);
DISPLAY 0.872340 (-5675 -3125);
PAINT GREEN (-5675 -3125);
DISPLAY INVISIBLE (-5675 -3125);
FORCEPROP 2 LAST CDS_LIB mstr_standard
J 0
(-6000 -3000);
PAINT MONO (-6000 -3000);
DISPLAY INVISIBLE (-6000 -3000);
FORCEPROP 2 LAST PATH I19
J 0
(-6250 -2950);
DISPLAY 1.021277 (-6250 -2950);
PAINT ORANGE (-6250 -2950);
DISPLAY INVISIBLE (-6250 -2950);
FORCEADD RES..1
(-5925 -3250);
FORCEPROP 1 LAST PART_NUMBER G21497-005
J 0
(-6325 -3300);
DISPLAY 0.617021 (-6325 -3300);
PAINT BLUE (-6325 -3300);
FORCEPROP 1 LAST TOLERANCE 5%
J 0
(-5800 -3250);
DISPLAY 0.617021 (-5800 -3250);
PAINT SKYBLUE (-5800 -3250);
FORCEPROP 1 LASTPIN (-6025 -3250) $PN 1
J 0
(-6013 -3238);
DISPLAY 0.617021 (-6013 -3238);
PAINT ORANGE (-6013 -3238);
FORCEPROP 1 LASTPIN (-5825 -3250) $PN 2
J 0
(-5863 -3238);
DISPLAY 0.617021 (-5863 -3238);
PAINT ORANGE (-5863 -3238);
FORCEPROP 1 LAST VALUE 0.0
J 2
(-5950 -3300);
DISPLAY 0.617021 (-5950 -3300);
PAINT SKYBLUE (-5950 -3300);
FORCEPROP 1 LAST MATERIAL CHIP
J 0
(-6200 -3250);
DISPLAY 0.617021 (-6200 -3250);
PAINT SKYBLUE (-6200 -3250);
FORCEPROP 1 LAST LOCATION R9F33
J 0
(-6325 -3250);
DISPLAY 0.617021 (-6325 -3250);
PAINT AQUA (-6325 -3250);
FORCEPROP 1 LAST PATH I20
J 0
(-5975 -3100);
DISPLAY 0.978723 (-5975 -3100);
PAINT WHITE (-5975 -3100);
DISPLAY INVISIBLE (-5975 -3100);
FORCEPROP 0 LAST CDS_SEC 1
J 0
(-5800 -3200);
PAINT MONO (-5800 -3200);
DISPLAY INVISIBLE (-5800 -3200);
FORCEPROP 1 LAST PACK_TYPE 0402
J 0
(-5675 -3400);
DISPLAY 0.978723 (-5675 -3400);
PAINT SKYBLUE (-5675 -3400);
DISPLAY INVISIBLE (-5675 -3400);
FORCEPROP 0 LAST BOM_COST SM_CONTROLLER
J 0
(-5975 -2950);
DISPLAY 1.021277 (-5975 -2950);
PAINT ORANGE (-5975 -2950);
DISPLAY INVISIBLE (-5975 -2950);
FORCEPROP 0 LAST ROOM BMC
J 0
(-5975 -3050);
DISPLAY 1.021277 (-5975 -3050);
PAINT ORANGE (-5975 -3050);
DISPLAY INVISIBLE (-5975 -3050);
FORCEPROP 2 LAST SEC_TYPE 0402
J 0
(-5975 -3050);
DISPLAY 1.021277 (-5975 -3050);
PAINT ORANGE (-5975 -3050);
DISPLAY INVISIBLE (-5975 -3050);
FORCEPROP 2 LAST SEC 1
J 0
(-5975 -3050);
DISPLAY 0.680851 (-5975 -3050);
PAINT MONO (-5975 -3050);
DISPLAY INVISIBLE (-5975 -3050);
FORCEPROP 2 LAST CDS_LIB mstr_discrete
J 0
(-5925 -3250);
PAINT ORANGE (-5925 -3250);
DISPLAY INVISIBLE (-5925 -3250);
FORCEPROP 1 LAST WATTAGE 1/16W
J 2
(-5950 -3400);
DISPLAY 0.978723 (-5950 -3400);
PAINT SKYBLUE (-5950 -3400);
DISPLAY INVISIBLE (-5950 -3400);
FORCEPROP 2 LAST CDS_LOCATION R9F33
J 0
(-6325 -3250);
DISPLAY 0.617021 (-6325 -3250);
PAINT AQUA (-6325 -3250);
DISPLAY INVISIBLE (-6325 -3250);
FORCEADD OFFPAGE..6
(-7750 -3250);
FORCEPROP 2 LAST $XR0 166 
J 0
(-8030 -3250);
DISPLAY 0.638298 (-8030 -3250);
PAINT MONO (-8030 -3250);
FORCEPROP 1 LAST COMMENT_BODY TRUE
J 0
(-7650 -3325);
DISPLAY 0.872340 (-7650 -3325);
PAINT GREEN (-7650 -3325);
DISPLAY INVISIBLE (-7650 -3325);
FORCEPROP 1 LAST OFFPAGE TRUE
J 0
(-7425 -3375);
DISPLAY 0.872340 (-7425 -3375);
PAINT GREEN (-7425 -3375);
DISPLAY INVISIBLE (-7425 -3375);
FORCEPROP 2 LAST PATH I21
J 0
(-8025 -3200);
DISPLAY 1.021277 (-8025 -3200);
PAINT ORANGE (-8025 -3200);
DISPLAY INVISIBLE (-8025 -3200);
FORCEPROP 2 LAST CDS_LIB mstr_standard
J 0
(-7750 -3250);
PAINT ORANGE (-7750 -3250);
DISPLAY INVISIBLE (-7750 -3250);
FORCEADD RES..2
(-7475 -3575);
FORCEPROP 1 LAST VALUE 348
J 0
(-7455 -3475);
DISPLAY 0.617021 (-7455 -3475);
PAINT SKYBLUE (-7455 -3475);
FORCEPROP 1 LAST LOCATION R9F20
J 0
(-7455 -3425);
DISPLAY 0.617021 (-7455 -3425);
PAINT AQUA (-7455 -3425);
FORCEPROP 1 LAST PART_NUMBER G21796-340
J 0
(-7435 -3700);
DISPLAY 0.617021 (-7435 -3700);
PAINT BLUE (-7435 -3700);
FORCEPROP 1 LASTPIN (-7475 -3675) $PN 2
J 0
(-7470 -3665);
DISPLAY 0.617021 (-7470 -3665);
PAINT ORANGE (-7470 -3665);
FORCEPROP 1 LASTPIN (-7475 -3475) $PN 1
J 0
(-7470 -3513);
DISPLAY 0.617021 (-7470 -3513);
PAINT ORANGE (-7470 -3513);
FORCEPROP 1 LAST TOLERANCE 1%
J 0
(-7330 -3575);
DISPLAY 0.617021 (-7330 -3575);
PAINT SKYBLUE (-7330 -3575);
FORCEPROP 1 LAST WATTAGE 1/16W
J 0
(-7360 -3625);
DISPLAY 0.617021 (-7360 -3625);
PAINT SKYBLUE (-7360 -3625);
FORCEPROP 1 LAST MATERIAL EMPTY
J 0
(-7385 -3675);
DISPLAY 0.617021 (-7385 -3675);
PAINT RED (-7385 -3675);
FORCEPROP 1 LAST PACK_TYPE 0402
J 0
(-7435 -3750);
DISPLAY 0.617021 (-7435 -3750);
PAINT SKYBLUE (-7435 -3750);
FORCEPROP 2 LAST CDS_LIB mstr_discrete
J 0
(-7475 -3575);
PAINT ORANGE (-7475 -3575);
DISPLAY INVISIBLE (-7475 -3575);
FORCEPROP 2 LAST CDS_LOCATION R9F20
J 0
(-7430 -3450);
DISPLAY 0.617021 (-7430 -3450);
PAINT AQUA (-7430 -3450);
DISPLAY INVISIBLE (-7430 -3450);
FORCEPROP 0 LAST ROOM BMC
J 0
(-7425 -3350);
DISPLAY 1.021277 (-7425 -3350);
PAINT ORANGE (-7425 -3350);
DISPLAY INVISIBLE (-7425 -3350);
FORCEPROP 2 LAST SEC_TYPE 0402
J 0
(-7425 -3350);
DISPLAY 1.021277 (-7425 -3350);
PAINT ORANGE (-7425 -3350);
DISPLAY INVISIBLE (-7425 -3350);
FORCEPROP 2 LAST SEC 1
J 0
(-7425 -3350);
DISPLAY 0.680851 (-7425 -3350);
PAINT MONO (-7425 -3350);
DISPLAY INVISIBLE (-7425 -3350);
FORCEPROP 0 LAST BOM_COST SM_CONTROLLER
J 0
(-7425 -3250);
DISPLAY 1.021277 (-7425 -3250);
PAINT ORANGE (-7425 -3250);
DISPLAY INVISIBLE (-7425 -3250);
FORCEPROP 0 LAST CDS_SEC 1
J 0
(-7450 -3375);
PAINT MONO (-7450 -3375);
DISPLAY INVISIBLE (-7450 -3375);
FORCEPROP 1 LAST PATH I22
J 0
(-7425 -3400);
DISPLAY 0.978723 (-7425 -3400);
PAINT WHITE (-7425 -3400);
DISPLAY INVISIBLE (-7425 -3400);
FORCEADD GND..1
(-7475 -3850);
FORCEPROP 3 LASTPIN (-7475 -3800) SIG_NAME GND\g
J 0
(-7465 -3790);
DISPLAY 0.659574 (-7465 -3790);
PAINT MONO (-7465 -3790);
DISPLAY INVISIBLE (-7465 -3790);
FORCEPROP 1 LAST HDL_POWER GND
J 0
(-7475 -3700);
DISPLAY 0.872340 (-7475 -3700);
PAINT GREEN (-7475 -3700);
DISPLAY INVISIBLE (-7475 -3700);
FORCEPROP 1 LAST BODY_TYPE PLUMBING
J 0
(-7520 -3893);
DISPLAY 0.340426 (-7520 -3893);
PAINT GREEN (-7520 -3893);
DISPLAY INVISIBLE (-7520 -3893);
FORCEPROP 2 LAST CDS_LIB mstr_symbols
J 0
(-7475 -3850);
PAINT ORANGE (-7475 -3850);
DISPLAY INVISIBLE (-7475 -3850);
FORCEPROP 1 LAST SIZE 1B
J 0
(-7400 -3900);
DISPLAY 0.872340 (-7400 -3900);
PAINT AQUA (-7400 -3900);
DISPLAY INVISIBLE (-7400 -3900);
FORCEPROP 1 LAST VOLTAGE 0.0V
J 0
(-7520 -3893);
DISPLAY 0.340426 (-7520 -3893);
PAINT SKYBLUE (-7520 -3893);
DISPLAY INVISIBLE (-7520 -3893);
FORCEPROP 1 LAST PATH I23
J 0
(-7400 -3850);
DISPLAY 0.872340 (-7400 -3850);
PAINT AQUA (-7400 -3850);
DISPLAY INVISIBLE (-7400 -3850);
FORCEADD OFFPAGE..1
(-5900 -3350);
FORCEPROP 2 LAST $XR2 190 
J 0
(-6152 -3386);
DISPLAY 0.638298 (-6152 -3386);
PAINT MONO (-6152 -3386);
FORCEPROP 2 LAST $XR0 158 
J 0
(-6152 -3350);
DISPLAY 0.638298 (-6152 -3350);
PAINT MONO (-6152 -3350);
FORCEPROP 2 LAST $XR1 183 
J 0
(-6272 -3350);
DISPLAY 0.638298 (-6272 -3350);
PAINT MONO (-6272 -3350);
FORCEPROP 1 LAST COMMENT_BODY TRUE
J 0
(-5775 -3450);
DISPLAY 0.872340 (-5775 -3450);
PAINT GREEN (-5775 -3450);
DISPLAY INVISIBLE (-5775 -3450);
FORCEPROP 1 LAST OFFPAGE TRUE
J 0
(-5575 -3475);
DISPLAY 0.872340 (-5575 -3475);
PAINT GREEN (-5575 -3475);
DISPLAY INVISIBLE (-5575 -3475);
FORCEPROP 2 LAST PATH I24
J 0
(-6150 -3300);
DISPLAY 1.021277 (-6150 -3300);
PAINT ORANGE (-6150 -3300);
DISPLAY INVISIBLE (-6150 -3300);
FORCEPROP 2 LAST CDS_LIB mstr_standard
J 0
(-5900 -3350);
PAINT ORANGE (-5900 -3350);
DISPLAY INVISIBLE (-5900 -3350);
FORCEADD OFFPAGE..1
(-6650 -3450);
FORCEPROP 2 LAST $XR0 191 
J 0
(-6902 -3450);
DISPLAY 0.638298 (-6902 -3450);
PAINT MONO (-6902 -3450);
FORCEPROP 2 LAST $XR3 184 
J 0
(-6902 -3486);
DISPLAY 0.638298 (-6902 -3486);
PAINT MONO (-6902 -3486);
FORCEPROP 2 LAST $XR2 146 
J 0
(-7142 -3450);
DISPLAY 0.638298 (-7142 -3450);
PAINT MONO (-7142 -3450);
FORCEPROP 2 LAST $XR1 134 
J 0
(-7022 -3450);
DISPLAY 0.638298 (-7022 -3450);
PAINT MONO (-7022 -3450);
FORCEPROP 1 LAST COMMENT_BODY TRUE
J 0
(-6525 -3550);
DISPLAY 0.872340 (-6525 -3550);
PAINT GREEN (-6525 -3550);
DISPLAY INVISIBLE (-6525 -3550);
FORCEPROP 1 LAST OFFPAGE TRUE
J 0
(-6325 -3575);
DISPLAY 0.872340 (-6325 -3575);
PAINT GREEN (-6325 -3575);
DISPLAY INVISIBLE (-6325 -3575);
FORCEPROP 2 LAST PATH I25
J 0
(-6900 -3400);
DISPLAY 1.021277 (-6900 -3400);
PAINT ORANGE (-6900 -3400);
DISPLAY INVISIBLE (-6900 -3400);
FORCEPROP 2 LAST CDS_LIB mstr_standard
J 0
(-6650 -3450);
PAINT ORANGE (-6650 -3450);
DISPLAY INVISIBLE (-6650 -3450);
FORCEADD OFFPAGE..1
(-6650 -3550);
FORCEPROP 2 LAST $XR0 114 
J 0
(-6902 -3550);
DISPLAY 0.638298 (-6902 -3550);
PAINT MONO (-6902 -3550);
FORCEPROP 2 LAST $XR1 ?
J 0
(-6902 -3550);
DISPLAY 0.638298 (-6902 -3550);
PAINT MONO (-6902 -3550);
FORCEPROP 1 LAST COMMENT_BODY TRUE
J 0
(-6525 -3650);
DISPLAY 0.872340 (-6525 -3650);
PAINT GREEN (-6525 -3650);
DISPLAY INVISIBLE (-6525 -3650);
FORCEPROP 1 LAST OFFPAGE TRUE
J 0
(-6325 -3675);
DISPLAY 0.872340 (-6325 -3675);
PAINT GREEN (-6325 -3675);
DISPLAY INVISIBLE (-6325 -3675);
FORCEPROP 2 LAST PATH I26
J 0
(-6900 -3500);
DISPLAY 1.021277 (-6900 -3500);
PAINT ORANGE (-6900 -3500);
DISPLAY INVISIBLE (-6900 -3500);
FORCEPROP 2 LAST CDS_LIB mstr_standard
J 0
(-6650 -3550);
PAINT ORANGE (-6650 -3550);
DISPLAY INVISIBLE (-6650 -3550);
FORCEADD OFFPAGE..1
(-6650 -3600);
FORCEPROP 2 LAST $XR0 114 
J 0
(-6902 -3600);
DISPLAY 0.638298 (-6902 -3600);
PAINT MONO (-6902 -3600);
FORCEPROP 2 LAST $XR1 ?
J 0
(-6902 -3600);
DISPLAY 0.638298 (-6902 -3600);
PAINT MONO (-6902 -3600);
FORCEPROP 1 LAST COMMENT_BODY TRUE
J 0
(-6525 -3700);
DISPLAY 0.872340 (-6525 -3700);
PAINT GREEN (-6525 -3700);
DISPLAY INVISIBLE (-6525 -3700);
FORCEPROP 1 LAST OFFPAGE TRUE
J 0
(-6325 -3725);
DISPLAY 0.872340 (-6325 -3725);
PAINT GREEN (-6325 -3725);
DISPLAY INVISIBLE (-6325 -3725);
FORCEPROP 2 LAST CDS_LIB mstr_standard
J 0
(-6650 -3600);
PAINT ORANGE (-6650 -3600);
DISPLAY INVISIBLE (-6650 -3600);
FORCEPROP 2 LAST PATH I27
J 0
(-6900 -3550);
DISPLAY 1.021277 (-6900 -3550);
PAINT ORANGE (-6900 -3550);
DISPLAY INVISIBLE (-6900 -3550);
FORCEADD OFFPAGE..1
(-6650 -3700);
FORCEPROP 2 LAST $XR0 116 
J 0
(-6902 -3700);
DISPLAY 0.638298 (-6902 -3700);
PAINT MONO (-6902 -3700);
FORCEPROP 2 LAST $XR1 ?
J 0
(-6902 -3700);
DISPLAY 0.638298 (-6902 -3700);
PAINT MONO (-6902 -3700);
FORCEPROP 1 LAST COMMENT_BODY TRUE
J 0
(-6525 -3800);
DISPLAY 0.872340 (-6525 -3800);
PAINT GREEN (-6525 -3800);
DISPLAY INVISIBLE (-6525 -3800);
FORCEPROP 1 LAST OFFPAGE TRUE
J 0
(-6325 -3825);
DISPLAY 0.872340 (-6325 -3825);
PAINT GREEN (-6325 -3825);
DISPLAY INVISIBLE (-6325 -3825);
FORCEPROP 2 LAST CDS_LIB mstr_standard
J 0
(-6650 -3700);
PAINT ORANGE (-6650 -3700);
DISPLAY INVISIBLE (-6650 -3700);
FORCEPROP 2 LAST PATH I28
J 0
(-6900 -3650);
DISPLAY 1.021277 (-6900 -3650);
PAINT ORANGE (-6900 -3650);
DISPLAY INVISIBLE (-6900 -3650);
FORCEADD OFFPAGE..1
(-6650 -3750);
FORCEPROP 2 LAST $XR0 116 
J 0
(-6902 -3750);
DISPLAY 0.638298 (-6902 -3750);
PAINT MONO (-6902 -3750);
FORCEPROP 2 LAST $XR1 ?
J 0
(-6902 -3750);
DISPLAY 0.638298 (-6902 -3750);
PAINT MONO (-6902 -3750);
FORCEPROP 1 LAST COMMENT_BODY TRUE
J 0
(-6525 -3850);
DISPLAY 0.872340 (-6525 -3850);
PAINT GREEN (-6525 -3850);
DISPLAY INVISIBLE (-6525 -3850);
FORCEPROP 1 LAST OFFPAGE TRUE
J 0
(-6325 -3875);
DISPLAY 0.872340 (-6325 -3875);
PAINT GREEN (-6325 -3875);
DISPLAY INVISIBLE (-6325 -3875);
FORCEPROP 2 LAST PATH I29
J 0
(-6900 -3700);
DISPLAY 1.021277 (-6900 -3700);
PAINT ORANGE (-6900 -3700);
DISPLAY INVISIBLE (-6900 -3700);
FORCEPROP 2 LAST CDS_LIB mstr_standard
J 0
(-6650 -3750);
PAINT ORANGE (-6650 -3750);
DISPLAY INVISIBLE (-6650 -3750);
FORCEADD RES..2
(-5450 -4350);
FORCEPROP 1 LAST WATTAGE 1/16W
J 0
(-5410 -4375);
DISPLAY 0.617021 (-5410 -4375);
PAINT SKYBLUE (-5410 -4375);
FORCEPROP 1 LAST TOLERANCE 1%
J 0
(-5405 -4325);
DISPLAY 0.617021 (-5405 -4325);
PAINT SKYBLUE (-5405 -4325);
FORCEPROP 1 LAST VALUE 100.0K
J 0
(-5405 -4275);
DISPLAY 0.617021 (-5405 -4275);
PAINT SKYBLUE (-5405 -4275);
FORCEPROP 1 LAST LOCATION R25W61
J 0
(-5405 -4225);
DISPLAY 0.617021 (-5405 -4225);
PAINT AQUA (-5405 -4225);
FORCEPROP 1 LAST PACK_TYPE 0402
J 0
(-5410 -4525);
DISPLAY 0.617021 (-5410 -4525);
PAINT SKYBLUE (-5410 -4525);
FORCEPROP 1 LAST MATERIAL CHIP
J 0
(-5410 -4425);
DISPLAY 0.617021 (-5410 -4425);
PAINT SKYBLUE (-5410 -4425);
FORCEPROP 1 LAST PART_NUMBER G21796-010
J 0
(-5410 -4475);
DISPLAY 0.617021 (-5410 -4475);
PAINT BLUE (-5410 -4475);
FORCEPROP 1 LASTPIN (-5450 -4450) $PN 2
J 0
(-5445 -4440);
DISPLAY 0.617021 (-5445 -4440);
PAINT ORANGE (-5445 -4440);
FORCEPROP 1 LASTPIN (-5450 -4250) $PN 1
J 0
(-5445 -4288);
DISPLAY 0.617021 (-5445 -4288);
PAINT ORANGE (-5445 -4288);
FORCEPROP 2 LAST CDS_LOCATION R25W61
J 0
(-5405 -4225);
DISPLAY 0.617021 (-5405 -4225);
PAINT AQUA (-5405 -4225);
DISPLAY INVISIBLE (-5405 -4225);
FORCEPROP 0 LAST CDS_SEC 1
J 0
(-5400 -4175);
PAINT MONO (-5400 -4175);
DISPLAY INVISIBLE (-5400 -4175);
FORCEPROP 2 LAST CDS_LIB mstr_discrete
J 0
(-5450 -4350);
PAINT ORANGE (-5450 -4350);
DISPLAY INVISIBLE (-5450 -4350);
FORCEPROP 2 LAST SEC 1
J 0
(-5400 -4125);
DISPLAY 0.680851 (-5400 -4125);
PAINT MONO (-5400 -4125);
DISPLAY INVISIBLE (-5400 -4125);
FORCEPROP 2 LAST SEC_TYPE 0402
J 0
(-5400 -4125);
DISPLAY 1.021277 (-5400 -4125);
PAINT ORANGE (-5400 -4125);
DISPLAY INVISIBLE (-5400 -4125);
FORCEPROP 0 LAST BOM_COST SM_CONTROLLER
J 0
(-5400 -4025);
DISPLAY 1.021277 (-5400 -4025);
PAINT ORANGE (-5400 -4025);
DISPLAY INVISIBLE (-5400 -4025);
FORCEPROP 0 LAST ROOM BMC
J 0
(-5400 -4125);
DISPLAY 0.617021 (-5400 -4125);
PAINT ORANGE (-5400 -4125);
DISPLAY INVISIBLE (-5400 -4125);
FORCEPROP 1 LAST PATH I30
J 0
(-5400 -4175);
DISPLAY 0.978723 (-5400 -4175);
PAINT WHITE (-5400 -4175);
DISPLAY INVISIBLE (-5400 -4175);
FORCEADD RES..2
(-5200 -4350);
FORCEPROP 1 LAST WATTAGE 1/16W
J 0
(-5160 -4375);
DISPLAY 0.617021 (-5160 -4375);
PAINT SKYBLUE (-5160 -4375);
FORCEPROP 1 LAST VALUE 100.0K
J 0
(-5155 -4275);
DISPLAY 0.617021 (-5155 -4275);
PAINT SKYBLUE (-5155 -4275);
FORCEPROP 1 LAST LOCATION R25W62
J 0
(-5155 -4225);
DISPLAY 0.617021 (-5155 -4225);
PAINT AQUA (-5155 -4225);
FORCEPROP 1 LAST MATERIAL CHIP
J 0
(-5160 -4425);
DISPLAY 0.617021 (-5160 -4425);
PAINT SKYBLUE (-5160 -4425);
FORCEPROP 1 LASTPIN (-5200 -4450) $PN 2
J 0
(-5195 -4440);
DISPLAY 0.617021 (-5195 -4440);
PAINT ORANGE (-5195 -4440);
FORCEPROP 1 LAST TOLERANCE 1%
J 0
(-5155 -4325);
DISPLAY 0.617021 (-5155 -4325);
PAINT SKYBLUE (-5155 -4325);
FORCEPROP 1 LASTPIN (-5200 -4250) $PN 1
J 0
(-5195 -4288);
DISPLAY 0.617021 (-5195 -4288);
PAINT ORANGE (-5195 -4288);
FORCEPROP 1 LAST PART_NUMBER G21796-010
J 0
(-5160 -4475);
DISPLAY 0.617021 (-5160 -4475);
PAINT BLUE (-5160 -4475);
FORCEPROP 1 LAST PACK_TYPE 0402
J 0
(-5160 -4525);
DISPLAY 0.617021 (-5160 -4525);
PAINT SKYBLUE (-5160 -4525);
FORCEPROP 2 LAST CDS_LOCATION R25W62
J 0
(-5155 -4225);
DISPLAY 0.617021 (-5155 -4225);
PAINT AQUA (-5155 -4225);
DISPLAY INVISIBLE (-5155 -4225);
FORCEPROP 1 LAST PATH I31
J 0
(-5150 -4175);
DISPLAY 0.978723 (-5150 -4175);
PAINT WHITE (-5150 -4175);
DISPLAY INVISIBLE (-5150 -4175);
FORCEPROP 0 LAST ROOM BMC
J 0
(-5150 -4125);
DISPLAY 0.617021 (-5150 -4125);
PAINT ORANGE (-5150 -4125);
DISPLAY INVISIBLE (-5150 -4125);
FORCEPROP 0 LAST BOM_COST SM_CONTROLLER
J 0
(-5150 -4025);
DISPLAY 1.021277 (-5150 -4025);
PAINT ORANGE (-5150 -4025);
DISPLAY INVISIBLE (-5150 -4025);
FORCEPROP 2 LAST SEC_TYPE 0402
J 0
(-5150 -4125);
DISPLAY 1.021277 (-5150 -4125);
PAINT ORANGE (-5150 -4125);
DISPLAY INVISIBLE (-5150 -4125);
FORCEPROP 2 LAST SEC 1
J 0
(-5150 -4125);
DISPLAY 0.680851 (-5150 -4125);
PAINT MONO (-5150 -4125);
DISPLAY INVISIBLE (-5150 -4125);
FORCEPROP 2 LAST CDS_LIB mstr_discrete
J 0
(-5200 -4350);
PAINT ORANGE (-5200 -4350);
DISPLAY INVISIBLE (-5200 -4350);
FORCEPROP 0 LAST CDS_SEC 1
J 0
(-5150 -4175);
PAINT MONO (-5150 -4175);
DISPLAY INVISIBLE (-5150 -4175);
FORCEADD GND..1
(-5200 -4700);
FORCEPROP 3 LASTPIN (-5200 -4650) SIG_NAME GND\g
J 0
(-5190 -4640);
DISPLAY 0.659574 (-5190 -4640);
PAINT MONO (-5190 -4640);
DISPLAY INVISIBLE (-5190 -4640);
FORCEPROP 1 LAST HDL_POWER GND
J 0
(-5200 -4550);
DISPLAY 0.872340 (-5200 -4550);
PAINT GREEN (-5200 -4550);
DISPLAY INVISIBLE (-5200 -4550);
FORCEPROP 1 LAST BODY_TYPE PLUMBING
J 0
(-5245 -4743);
DISPLAY 0.340426 (-5245 -4743);
PAINT GREEN (-5245 -4743);
DISPLAY INVISIBLE (-5245 -4743);
FORCEPROP 1 LAST PATH I32
J 0
(-5125 -4700);
DISPLAY 0.872340 (-5125 -4700);
PAINT AQUA (-5125 -4700);
DISPLAY INVISIBLE (-5125 -4700);
FORCEPROP 1 LAST SIZE 1B
J 0
(-5125 -4750);
DISPLAY 0.872340 (-5125 -4750);
PAINT AQUA (-5125 -4750);
DISPLAY INVISIBLE (-5125 -4750);
FORCEPROP 1 LAST VOLTAGE 0.0V
J 0
(-5245 -4743);
DISPLAY 0.340426 (-5245 -4743);
PAINT SKYBLUE (-5245 -4743);
DISPLAY INVISIBLE (-5245 -4743);
FORCEPROP 2 LAST CDS_LIB mstr_symbols
J 0
(-5200 -4700);
PAINT ORANGE (-5200 -4700);
DISPLAY INVISIBLE (-5200 -4700);
FORCEADD GND..1
(-5450 -4700);
FORCEPROP 3 LASTPIN (-5450 -4650) SIG_NAME GND\g
J 0
(-5440 -4640);
DISPLAY 0.659574 (-5440 -4640);
PAINT MONO (-5440 -4640);
DISPLAY INVISIBLE (-5440 -4640);
FORCEPROP 1 LAST HDL_POWER GND
J 0
(-5450 -4550);
DISPLAY 0.872340 (-5450 -4550);
PAINT GREEN (-5450 -4550);
DISPLAY INVISIBLE (-5450 -4550);
FORCEPROP 1 LAST BODY_TYPE PLUMBING
J 0
(-5495 -4743);
DISPLAY 0.340426 (-5495 -4743);
PAINT GREEN (-5495 -4743);
DISPLAY INVISIBLE (-5495 -4743);
FORCEPROP 1 LAST PATH I33
J 0
(-5375 -4700);
DISPLAY 0.872340 (-5375 -4700);
PAINT AQUA (-5375 -4700);
DISPLAY INVISIBLE (-5375 -4700);
FORCEPROP 1 LAST SIZE 1B
J 0
(-5375 -4750);
DISPLAY 0.872340 (-5375 -4750);
PAINT AQUA (-5375 -4750);
DISPLAY INVISIBLE (-5375 -4750);
FORCEPROP 1 LAST VOLTAGE 0.0V
J 0
(-5495 -4743);
DISPLAY 0.340426 (-5495 -4743);
PAINT SKYBLUE (-5495 -4743);
DISPLAY INVISIBLE (-5495 -4743);
FORCEPROP 2 LAST CDS_LIB mstr_symbols
J 0
(-5450 -4700);
PAINT ORANGE (-5450 -4700);
DISPLAY INVISIBLE (-5450 -4700);
FORCEADD RES..2
(-5700 -4350);
FORCEPROP 1 LAST PART_NUMBER G21796-010
J 0
(-5660 -4475);
DISPLAY 0.617021 (-5660 -4475);
PAINT BLUE (-5660 -4475);
FORCEPROP 1 LAST MATERIAL CHIP
J 0
(-5660 -4425);
DISPLAY 0.617021 (-5660 -4425);
PAINT SKYBLUE (-5660 -4425);
FORCEPROP 1 LASTPIN (-5700 -4450) $PN 2
J 0
(-5695 -4440);
DISPLAY 0.617021 (-5695 -4440);
PAINT ORANGE (-5695 -4440);
FORCEPROP 1 LAST PACK_TYPE 0402
J 0
(-5660 -4525);
DISPLAY 0.617021 (-5660 -4525);
PAINT SKYBLUE (-5660 -4525);
FORCEPROP 1 LAST LOCATION R25W60
J 0
(-5655 -4225);
DISPLAY 0.617021 (-5655 -4225);
PAINT AQUA (-5655 -4225);
FORCEPROP 1 LASTPIN (-5700 -4250) $PN 1
J 0
(-5695 -4288);
DISPLAY 0.617021 (-5695 -4288);
PAINT ORANGE (-5695 -4288);
FORCEPROP 1 LAST TOLERANCE 1%
J 0
(-5655 -4325);
DISPLAY 0.617021 (-5655 -4325);
PAINT SKYBLUE (-5655 -4325);
FORCEPROP 1 LAST WATTAGE 1/16W
J 0
(-5660 -4375);
DISPLAY 0.617021 (-5660 -4375);
PAINT SKYBLUE (-5660 -4375);
FORCEPROP 1 LAST VALUE 100.0K
J 0
(-5655 -4275);
DISPLAY 0.617021 (-5655 -4275);
PAINT SKYBLUE (-5655 -4275);
FORCEPROP 2 LAST CDS_LOCATION R25W60
J 0
(-5655 -4225);
DISPLAY 0.617021 (-5655 -4225);
PAINT AQUA (-5655 -4225);
DISPLAY INVISIBLE (-5655 -4225);
FORCEPROP 0 LAST CDS_SEC 1
J 0
(-5650 -4175);
PAINT MONO (-5650 -4175);
DISPLAY INVISIBLE (-5650 -4175);
FORCEPROP 2 LAST CDS_LIB mstr_discrete
J 0
(-5700 -4350);
PAINT ORANGE (-5700 -4350);
DISPLAY INVISIBLE (-5700 -4350);
FORCEPROP 2 LAST SEC 1
J 0
(-5650 -4125);
DISPLAY 0.680851 (-5650 -4125);
PAINT MONO (-5650 -4125);
DISPLAY INVISIBLE (-5650 -4125);
FORCEPROP 2 LAST SEC_TYPE 0402
J 0
(-5650 -4125);
DISPLAY 1.021277 (-5650 -4125);
PAINT ORANGE (-5650 -4125);
DISPLAY INVISIBLE (-5650 -4125);
FORCEPROP 0 LAST ROOM BMC
J 0
(-5650 -4125);
DISPLAY 0.617021 (-5650 -4125);
PAINT ORANGE (-5650 -4125);
DISPLAY INVISIBLE (-5650 -4125);
FORCEPROP 0 LAST BOM_COST SM_CONTROLLER
J 0
(-5650 -4025);
DISPLAY 1.021277 (-5650 -4025);
PAINT ORANGE (-5650 -4025);
DISPLAY INVISIBLE (-5650 -4025);
FORCEPROP 1 LAST PATH I34
J 0
(-5650 -4175);
DISPLAY 0.978723 (-5650 -4175);
PAINT WHITE (-5650 -4175);
DISPLAY INVISIBLE (-5650 -4175);
FORCEADD GND..1
(-5700 -4700);
FORCEPROP 3 LASTPIN (-5700 -4650) SIG_NAME GND\g
J 0
(-5690 -4640);
DISPLAY 0.659574 (-5690 -4640);
PAINT MONO (-5690 -4640);
DISPLAY INVISIBLE (-5690 -4640);
FORCEPROP 1 LAST HDL_POWER GND
J 0
(-5700 -4550);
DISPLAY 0.872340 (-5700 -4550);
PAINT GREEN (-5700 -4550);
DISPLAY INVISIBLE (-5700 -4550);
FORCEPROP 1 LAST BODY_TYPE PLUMBING
J 0
(-5745 -4743);
DISPLAY 0.340426 (-5745 -4743);
PAINT GREEN (-5745 -4743);
DISPLAY INVISIBLE (-5745 -4743);
FORCEPROP 1 LAST PATH I35
J 0
(-5625 -4700);
DISPLAY 0.872340 (-5625 -4700);
PAINT AQUA (-5625 -4700);
DISPLAY INVISIBLE (-5625 -4700);
FORCEPROP 1 LAST SIZE 1B
J 0
(-5625 -4750);
DISPLAY 0.872340 (-5625 -4750);
PAINT AQUA (-5625 -4750);
DISPLAY INVISIBLE (-5625 -4750);
FORCEPROP 2 LAST CDS_LIB mstr_symbols
J 0
(-5700 -4700);
PAINT ORANGE (-5700 -4700);
DISPLAY INVISIBLE (-5700 -4700);
FORCEPROP 1 LAST VOLTAGE 0.0V
J 0
(-5745 -4743);
DISPLAY 0.340426 (-5745 -4743);
PAINT SKYBLUE (-5745 -4743);
DISPLAY INVISIBLE (-5745 -4743);
FORCEADD RES..2
(-5950 -4325);
FORCEPROP 1 LAST MATERIAL CHIP
J 0
(-5910 -4400);
DISPLAY 0.617021 (-5910 -4400);
PAINT SKYBLUE (-5910 -4400);
FORCEPROP 1 LAST WATTAGE 1/16W
J 0
(-5910 -4350);
DISPLAY 0.617021 (-5910 -4350);
PAINT SKYBLUE (-5910 -4350);
FORCEPROP 1 LAST PART_NUMBER G21796-010
J 0
(-5910 -4450);
DISPLAY 0.617021 (-5910 -4450);
PAINT BLUE (-5910 -4450);
FORCEPROP 1 LAST TOLERANCE 1%
J 0
(-5905 -4300);
DISPLAY 0.617021 (-5905 -4300);
PAINT SKYBLUE (-5905 -4300);
FORCEPROP 1 LAST VALUE 100.0K
J 0
(-5905 -4250);
DISPLAY 0.617021 (-5905 -4250);
PAINT SKYBLUE (-5905 -4250);
FORCEPROP 1 LASTPIN (-5950 -4225) $PN 1
J 0
(-5945 -4263);
DISPLAY 0.617021 (-5945 -4263);
PAINT ORANGE (-5945 -4263);
FORCEPROP 1 LASTPIN (-5950 -4425) $PN 2
J 0
(-5945 -4415);
DISPLAY 0.617021 (-5945 -4415);
PAINT ORANGE (-5945 -4415);
FORCEPROP 1 LAST LOCATION R25W64
J 0
(-5905 -4200);
DISPLAY 0.617021 (-5905 -4200);
PAINT AQUA (-5905 -4200);
FORCEPROP 1 LAST PACK_TYPE 0402
J 0
(-5910 -4500);
DISPLAY 0.617021 (-5910 -4500);
PAINT SKYBLUE (-5910 -4500);
FORCEPROP 2 LAST CDS_LOCATION R25W64
J 0
(-5905 -4200);
DISPLAY 0.617021 (-5905 -4200);
PAINT AQUA (-5905 -4200);
DISPLAY INVISIBLE (-5905 -4200);
FORCEPROP 1 LAST PATH I36
J 0
(-5900 -4150);
DISPLAY 0.978723 (-5900 -4150);
PAINT WHITE (-5900 -4150);
DISPLAY INVISIBLE (-5900 -4150);
FORCEPROP 0 LAST ROOM BMC
J 0
(-5900 -4100);
DISPLAY 0.617021 (-5900 -4100);
PAINT ORANGE (-5900 -4100);
DISPLAY INVISIBLE (-5900 -4100);
FORCEPROP 0 LAST BOM_COST SM_CONTROLLER
J 0
(-5900 -4000);
DISPLAY 1.021277 (-5900 -4000);
PAINT ORANGE (-5900 -4000);
DISPLAY INVISIBLE (-5900 -4000);
FORCEPROP 2 LAST SEC 1
J 0
(-5900 -4100);
DISPLAY 0.680851 (-5900 -4100);
PAINT MONO (-5900 -4100);
DISPLAY INVISIBLE (-5900 -4100);
FORCEPROP 2 LAST SEC_TYPE 0402
J 0
(-5900 -4100);
DISPLAY 1.021277 (-5900 -4100);
PAINT ORANGE (-5900 -4100);
DISPLAY INVISIBLE (-5900 -4100);
FORCEPROP 2 LAST CDS_LIB mstr_discrete
J 0
(-5950 -4325);
PAINT ORANGE (-5950 -4325);
DISPLAY INVISIBLE (-5950 -4325);
FORCEPROP 0 LAST CDS_SEC 1
J 0
(-5900 -4150);
PAINT MONO (-5900 -4150);
DISPLAY INVISIBLE (-5900 -4150);
FORCEADD GND..1
(-5950 -4700);
FORCEPROP 3 LASTPIN (-5950 -4650) SIG_NAME GND\g
J 0
(-5940 -4640);
DISPLAY 0.659574 (-5940 -4640);
PAINT MONO (-5940 -4640);
DISPLAY INVISIBLE (-5940 -4640);
FORCEPROP 1 LAST HDL_POWER GND
J 0
(-5950 -4550);
DISPLAY 0.872340 (-5950 -4550);
PAINT GREEN (-5950 -4550);
DISPLAY INVISIBLE (-5950 -4550);
FORCEPROP 1 LAST BODY_TYPE PLUMBING
J 0
(-5995 -4743);
DISPLAY 0.340426 (-5995 -4743);
PAINT GREEN (-5995 -4743);
DISPLAY INVISIBLE (-5995 -4743);
FORCEPROP 1 LAST PATH I37
J 0
(-5875 -4700);
DISPLAY 0.872340 (-5875 -4700);
PAINT AQUA (-5875 -4700);
DISPLAY INVISIBLE (-5875 -4700);
FORCEPROP 1 LAST SIZE 1B
J 0
(-5875 -4750);
DISPLAY 0.872340 (-5875 -4750);
PAINT AQUA (-5875 -4750);
DISPLAY INVISIBLE (-5875 -4750);
FORCEPROP 1 LAST VOLTAGE 0.0V
J 0
(-5995 -4743);
DISPLAY 0.340426 (-5995 -4743);
PAINT SKYBLUE (-5995 -4743);
DISPLAY INVISIBLE (-5995 -4743);
FORCEPROP 2 LAST CDS_LIB mstr_symbols
J 0
(-5950 -4700);
PAINT ORANGE (-5950 -4700);
DISPLAY INVISIBLE (-5950 -4700);
FORCEADD RES..2
(-6200 -4325);
FORCEPROP 1 LAST WATTAGE 1/16W
J 0
(-6160 -4350);
DISPLAY 0.617021 (-6160 -4350);
PAINT SKYBLUE (-6160 -4350);
FORCEPROP 1 LAST TOLERANCE 1%
J 0
(-6155 -4300);
DISPLAY 0.617021 (-6155 -4300);
PAINT SKYBLUE (-6155 -4300);
FORCEPROP 1 LAST LOCATION R25W65
J 0
(-6155 -4200);
DISPLAY 0.617021 (-6155 -4200);
PAINT AQUA (-6155 -4200);
FORCEPROP 1 LAST MATERIAL CHIP
J 0
(-6160 -4400);
DISPLAY 0.617021 (-6160 -4400);
PAINT SKYBLUE (-6160 -4400);
FORCEPROP 1 LASTPIN (-6200 -4425) $PN 2
J 0
(-6195 -4415);
DISPLAY 0.617021 (-6195 -4415);
PAINT ORANGE (-6195 -4415);
FORCEPROP 1 LAST PART_NUMBER G21796-010
J 0
(-6160 -4450);
DISPLAY 0.617021 (-6160 -4450);
PAINT BLUE (-6160 -4450);
FORCEPROP 1 LAST PACK_TYPE 0402
J 0
(-6160 -4500);
DISPLAY 0.617021 (-6160 -4500);
PAINT SKYBLUE (-6160 -4500);
FORCEPROP 1 LAST VALUE 100.0K
J 0
(-6155 -4250);
DISPLAY 0.617021 (-6155 -4250);
PAINT SKYBLUE (-6155 -4250);
FORCEPROP 1 LASTPIN (-6200 -4225) $PN 1
J 0
(-6195 -4263);
DISPLAY 0.617021 (-6195 -4263);
PAINT ORANGE (-6195 -4263);
FORCEPROP 2 LAST CDS_LOCATION R25W65
J 0
(-6155 -4200);
DISPLAY 0.617021 (-6155 -4200);
PAINT AQUA (-6155 -4200);
DISPLAY INVISIBLE (-6155 -4200);
FORCEPROP 1 LAST PATH I38
J 0
(-6150 -4150);
DISPLAY 0.978723 (-6150 -4150);
PAINT WHITE (-6150 -4150);
DISPLAY INVISIBLE (-6150 -4150);
FORCEPROP 0 LAST ROOM BMC
J 0
(-6150 -4100);
DISPLAY 0.617021 (-6150 -4100);
PAINT ORANGE (-6150 -4100);
DISPLAY INVISIBLE (-6150 -4100);
FORCEPROP 0 LAST BOM_COST SM_CONTROLLER
J 0
(-6150 -4000);
DISPLAY 1.021277 (-6150 -4000);
PAINT ORANGE (-6150 -4000);
DISPLAY INVISIBLE (-6150 -4000);
FORCEPROP 2 LAST SEC 1
J 0
(-6150 -4100);
DISPLAY 0.680851 (-6150 -4100);
PAINT MONO (-6150 -4100);
DISPLAY INVISIBLE (-6150 -4100);
FORCEPROP 2 LAST SEC_TYPE 0402
J 0
(-6150 -4100);
DISPLAY 1.021277 (-6150 -4100);
PAINT ORANGE (-6150 -4100);
DISPLAY INVISIBLE (-6150 -4100);
FORCEPROP 2 LAST CDS_LIB mstr_discrete
J 0
(-6200 -4325);
PAINT ORANGE (-6200 -4325);
DISPLAY INVISIBLE (-6200 -4325);
FORCEPROP 0 LAST CDS_SEC 1
J 0
(-6150 -4150);
PAINT MONO (-6150 -4150);
DISPLAY INVISIBLE (-6150 -4150);
FORCEADD GND..1
(-6200 -4700);
FORCEPROP 3 LASTPIN (-6200 -4650) SIG_NAME GND\g
J 0
(-6190 -4640);
DISPLAY 0.659574 (-6190 -4640);
PAINT MONO (-6190 -4640);
DISPLAY INVISIBLE (-6190 -4640);
FORCEPROP 1 LAST HDL_POWER GND
J 0
(-6200 -4550);
DISPLAY 0.872340 (-6200 -4550);
PAINT GREEN (-6200 -4550);
DISPLAY INVISIBLE (-6200 -4550);
FORCEPROP 1 LAST BODY_TYPE PLUMBING
J 0
(-6245 -4743);
DISPLAY 0.340426 (-6245 -4743);
PAINT GREEN (-6245 -4743);
DISPLAY INVISIBLE (-6245 -4743);
FORCEPROP 1 LAST PATH I39
J 0
(-6125 -4700);
DISPLAY 0.872340 (-6125 -4700);
PAINT AQUA (-6125 -4700);
DISPLAY INVISIBLE (-6125 -4700);
FORCEPROP 1 LAST SIZE 1B
J 0
(-6125 -4750);
DISPLAY 0.872340 (-6125 -4750);
PAINT AQUA (-6125 -4750);
DISPLAY INVISIBLE (-6125 -4750);
FORCEPROP 1 LAST VOLTAGE 0.0V
J 0
(-6245 -4743);
DISPLAY 0.340426 (-6245 -4743);
PAINT SKYBLUE (-6245 -4743);
DISPLAY INVISIBLE (-6245 -4743);
FORCEPROP 2 LAST CDS_LIB mstr_symbols
J 0
(-6200 -4700);
PAINT ORANGE (-6200 -4700);
DISPLAY INVISIBLE (-6200 -4700);
FORCEADD OFFPAGE..1
(-6125 -2450);
FORCEPROP 2 LAST $XR0 120 
J 0
(-6677 -2450);
DISPLAY 0.638298 (-6677 -2450);
PAINT MONO (-6677 -2450);
FORCEPROP 2 LAST $XR1 133 
J 0
(-6797 -2450);
DISPLAY 0.638298 (-6797 -2450);
PAINT MONO (-6797 -2450);
FORCEPROP 1 LAST COMMENT_BODY TRUE
J 0
(-6000 -2550);
DISPLAY 0.872340 (-6000 -2550);
PAINT GREEN (-6000 -2550);
DISPLAY INVISIBLE (-6000 -2550);
FORCEPROP 1 LAST OFFPAGE TRUE
J 0
(-5800 -2575);
DISPLAY 0.872340 (-5800 -2575);
PAINT GREEN (-5800 -2575);
DISPLAY INVISIBLE (-5800 -2575);
FORCEPROP 2 LAST CDS_LIB mstr_standard
J 0
(-6125 -2450);
PAINT MONO (-6125 -2450);
DISPLAY INVISIBLE (-6125 -2450);
FORCEPROP 2 LAST PATH I4
J 0
(-6075 -2375);
DISPLAY 1.021277 (-6075 -2375);
PAINT ORANGE (-6075 -2375);
DISPLAY INVISIBLE (-6075 -2375);
FORCEPROP 2 LAST ROOM BMC
J 0
(-6375 -2375);
DISPLAY 1.361702 (-6375 -2375);
PAINT ORANGE (-6375 -2375);
DISPLAY INVISIBLE (-6375 -2375);
FORCEPROP 2 LAST BOM_COST SM_CONTROLLER
J 0
(-5675 -2400);
PAINT MONO (-5675 -2400);
DISPLAY INVISIBLE (-5675 -2400);
FORCEADD OFFPAGE..2
(-1725 -3100);
FORCEPROP 2 LAST $XR0 151 
J 0
(-1536 -3100);
DISPLAY 0.638298 (-1536 -3100);
PAINT MONO (-1536 -3100);
DISPLAY INVISIBLE (-1536 -3100);
FORCEPROP 2 LAST $XR1 183 
J 0
(-1536 -3100);
DISPLAY 0.638298 (-1536 -3100);
PAINT MONO (-1536 -3100);
DISPLAY INVISIBLE (-1536 -3100);
FORCEPROP 2 LAST $XR2 190 
J 0
(-1536 -3100);
DISPLAY 0.638298 (-1536 -3100);
PAINT MONO (-1536 -3100);
DISPLAY INVISIBLE (-1536 -3100);
FORCEPROP 2 LAST $XR3 158 
J 0
(-1536 -3100);
DISPLAY 0.638298 (-1536 -3100);
PAINT MONO (-1536 -3100);
DISPLAY INVISIBLE (-1536 -3100);
FORCEPROP 1 LAST COMMENT_BODY TRUE
J 0
(-1770 -3195);
DISPLAY 0.872340 (-1770 -3195);
PAINT GREEN (-1770 -3195);
DISPLAY INVISIBLE (-1770 -3195);
FORCEPROP 1 LAST OFFPAGE TRUE
J 0
(-1400 -3225);
DISPLAY 0.872340 (-1400 -3225);
PAINT GREEN (-1400 -3225);
DISPLAY INVISIBLE (-1400 -3225);
FORCEPROP 2 LAST CDS_LIB mstr_standard
J 0
(-1725 -3100);
PAINT MONO (-1725 -3100);
DISPLAY INVISIBLE (-1725 -3100);
FORCEPROP 2 LAST PATH I41
J 0
(-1550 -3025);
DISPLAY 1.021277 (-1550 -3025);
PAINT ORANGE (-1550 -3025);
DISPLAY INVISIBLE (-1550 -3025);
FORCEADD OFFPAGE..2
(-525 -3700);
FORCEPROP 2 LAST $XR0 116 
J 0
(-336 -3700);
DISPLAY 0.638298 (-336 -3700);
PAINT MONO (-336 -3700);
FORCEPROP 1 LAST COMMENT_BODY TRUE
J 0
(-570 -3795);
DISPLAY 0.872340 (-570 -3795);
PAINT GREEN (-570 -3795);
DISPLAY INVISIBLE (-570 -3795);
FORCEPROP 1 LAST OFFPAGE TRUE
J 0
(-200 -3825);
DISPLAY 0.872340 (-200 -3825);
PAINT GREEN (-200 -3825);
DISPLAY INVISIBLE (-200 -3825);
FORCEPROP 2 LAST PATH I42
J 0
(-325 -3650);
DISPLAY 1.021277 (-325 -3650);
PAINT ORANGE (-325 -3650);
DISPLAY INVISIBLE (-325 -3650);
FORCEPROP 2 LAST CDS_LIB mstr_standard
J 0
(-525 -3700);
PAINT ORANGE (-525 -3700);
DISPLAY INVISIBLE (-525 -3700);
FORCEADD OFFPAGE..2
(-525 -3400);
FORCEPROP 2 LAST $XR0 116 
J 0
(-336 -3400);
DISPLAY 0.638298 (-336 -3400);
PAINT MONO (-336 -3400);
FORCEPROP 1 LAST COMMENT_BODY TRUE
J 0
(-570 -3495);
DISPLAY 0.872340 (-570 -3495);
PAINT GREEN (-570 -3495);
DISPLAY INVISIBLE (-570 -3495);
FORCEPROP 1 LAST OFFPAGE TRUE
J 0
(-200 -3525);
DISPLAY 0.872340 (-200 -3525);
PAINT GREEN (-200 -3525);
DISPLAY INVISIBLE (-200 -3525);
FORCEPROP 2 LAST CDS_LIB mstr_standard
J 0
(-525 -3400);
PAINT ORANGE (-525 -3400);
DISPLAY INVISIBLE (-525 -3400);
FORCEPROP 2 LAST PATH I43
J 0
(-325 -3350);
DISPLAY 1.021277 (-325 -3350);
PAINT ORANGE (-325 -3350);
DISPLAY INVISIBLE (-325 -3350);
FORCEADD CAP_A..2
(-1275 -3700);
FORCEPROP 1 LAST MATERIAL EMPTY
J 0
(-1275 -3850);
DISPLAY 0.617021 (-1275 -3850);
PAINT RED (-1275 -3850);
FORCEPROP 1 LASTPIN (-1175 -3700) $PN 2
J 0
(-1190 -3685);
DISPLAY 0.617021 (-1190 -3685);
PAINT ORANGE (-1190 -3685);
FORCEPROP 1 LAST VOLTAGE 16V
J 0
(-1200 -3800);
DISPLAY 0.617021 (-1200 -3800);
PAINT SKYBLUE (-1200 -3800);
FORCEPROP 1 LAST PART_NUMBER A36096-030
J 1
(-1275 -3925);
DISPLAY 0.617021 (-1275 -3925);
PAINT BLUE (-1275 -3925);
FORCEPROP 1 LAST LOCATION C25W21
J 1
(-1275 -3600);
DISPLAY 0.617021 (-1275 -3600);
PAINT AQUA (-1275 -3600);
FORCEPROP 1 LAST VALUE 0.1UF
J 2
(-1300 -3825);
DISPLAY 0.617021 (-1300 -3825);
PAINT SKYBLUE (-1300 -3825);
FORCEPROP 1 LASTPIN (-1375 -3700) $PN 1
J 0
(-1385 -3685);
DISPLAY 0.617021 (-1385 -3685);
PAINT ORANGE (-1385 -3685);
FORCEPROP 1 LAST TOLERANCE 10%
J 2
(-1300 -3850);
DISPLAY 0.617021 (-1300 -3850);
PAINT SKYBLUE (-1300 -3850);
FORCEPROP 1 LAST PACK_TYPE 0402V
J 1
(-1275 -3900);
DISPLAY 0.617021 (-1275 -3900);
PAINT SKYBLUE (-1275 -3900);
FORCEPROP 2 LAST CDS_LOCATION C25W21
J 1
(-1275 -3600);
DISPLAY 0.617021 (-1275 -3600);
PAINT AQUA (-1275 -3600);
DISPLAY INVISIBLE (-1275 -3600);
FORCEPROP 0 LAST BOM_COST SM_CONTROLLER
J 0
(-1275 -3500);
DISPLAY 1.021277 (-1275 -3500);
PAINT ORANGE (-1275 -3500);
DISPLAY INVISIBLE (-1275 -3500);
FORCEPROP 2 LAST SEC 1
J 0
(-1275 -3450);
DISPLAY 0.680851 (-1275 -3450);
PAINT MONO (-1275 -3450);
DISPLAY INVISIBLE (-1275 -3450);
FORCEPROP 2 LAST SEC_TYPE 0402V
J 0
(-1275 -3450);
DISPLAY 1.021277 (-1275 -3450);
PAINT ORANGE (-1275 -3450);
DISPLAY INVISIBLE (-1275 -3450);
FORCEPROP 0 LAST ROOM BMC
J 0
(-1275 -3550);
DISPLAY 1.021277 (-1275 -3550);
PAINT ORANGE (-1275 -3550);
DISPLAY INVISIBLE (-1275 -3550);
FORCEPROP 2 LAST CDS_LIB dev_discrete
J 0
(-1275 -3700);
PAINT ORANGE (-1275 -3700);
DISPLAY INVISIBLE (-1275 -3700);
FORCEPROP 0 LAST CDS_SEC 1
J 0
(-1275 -3550);
PAINT MONO (-1275 -3550);
DISPLAY INVISIBLE (-1275 -3550);
FORCEPROP 1 LAST PATH I44
J 0
(-1275 -3500);
DISPLAY 0.978723 (-1275 -3500);
PAINT WHITE (-1275 -3500);
DISPLAY INVISIBLE (-1275 -3500);
FORCEADD CAP_A..2
(-1650 -3400);
FORCEPROP 1 LASTPIN (-1750 -3400) $PN 1
J 0
(-1760 -3385);
DISPLAY 0.617021 (-1760 -3385);
PAINT ORANGE (-1760 -3385);
FORCEPROP 1 LASTPIN (-1550 -3400) $PN 2
J 0
(-1565 -3385);
DISPLAY 0.617021 (-1565 -3385);
PAINT ORANGE (-1565 -3385);
FORCEPROP 1 LAST VALUE 0.1UF
J 2
(-1650 -3500);
DISPLAY 0.617021 (-1650 -3500);
PAINT SKYBLUE (-1650 -3500);
FORCEPROP 1 LAST TOLERANCE 10%
J 2
(-1650 -3550);
DISPLAY 0.617021 (-1650 -3550);
PAINT SKYBLUE (-1650 -3550);
FORCEPROP 1 LAST LOCATION C25W20
J 1
(-1650 -3300);
DISPLAY 0.617021 (-1650 -3300);
PAINT AQUA (-1650 -3300);
FORCEPROP 1 LAST VOLTAGE 16V
J 0
(-1525 -3500);
DISPLAY 0.617021 (-1525 -3500);
PAINT SKYBLUE (-1525 -3500);
FORCEPROP 1 LAST MATERIAL EMPTY
J 0
(-1650 -3550);
DISPLAY 0.617021 (-1650 -3550);
PAINT RED (-1650 -3550);
FORCEPROP 1 LAST PACK_TYPE 0402V
J 1
(-1650 -3600);
DISPLAY 0.617021 (-1650 -3600);
PAINT SKYBLUE (-1650 -3600);
FORCEPROP 1 LAST PART_NUMBER A36096-030
J 1
(-1600 -3650);
DISPLAY 0.617021 (-1600 -3650);
PAINT BLUE (-1600 -3650);
FORCEPROP 2 LAST CDS_LOCATION C25W20
J 1
(-1650 -3300);
DISPLAY 0.617021 (-1650 -3300);
PAINT AQUA (-1650 -3300);
DISPLAY INVISIBLE (-1650 -3300);
FORCEPROP 0 LAST CDS_SEC 1
J 0
(-1650 -3250);
PAINT MONO (-1650 -3250);
DISPLAY INVISIBLE (-1650 -3250);
FORCEPROP 2 LAST CDS_LIB dev_discrete
J 0
(-1650 -3400);
PAINT ORANGE (-1650 -3400);
DISPLAY INVISIBLE (-1650 -3400);
FORCEPROP 0 LAST ROOM BMC
J 0
(-1650 -3250);
DISPLAY 1.021277 (-1650 -3250);
PAINT ORANGE (-1650 -3250);
DISPLAY INVISIBLE (-1650 -3250);
FORCEPROP 2 LAST SEC_TYPE 0402V
J 0
(-1650 -3150);
DISPLAY 1.021277 (-1650 -3150);
PAINT ORANGE (-1650 -3150);
DISPLAY INVISIBLE (-1650 -3150);
FORCEPROP 2 LAST SEC 1
J 0
(-1650 -3150);
DISPLAY 0.680851 (-1650 -3150);
PAINT MONO (-1650 -3150);
DISPLAY INVISIBLE (-1650 -3150);
FORCEPROP 0 LAST BOM_COST SM_CONTROLLER
J 0
(-1650 -3200);
DISPLAY 1.021277 (-1650 -3200);
PAINT ORANGE (-1650 -3200);
DISPLAY INVISIBLE (-1650 -3200);
FORCEPROP 1 LAST PATH I45
J 0
(-1650 -3200);
DISPLAY 0.978723 (-1650 -3200);
PAINT WHITE (-1650 -3200);
DISPLAY INVISIBLE (-1650 -3200);
FORCEADD RES..1
(-1325 -3200);
FORCEPROP 1 LAST PART_NUMBER G21796-016
J 0
(-1350 -3375);
DISPLAY 0.617021 (-1350 -3375);
PAINT BLUE (-1350 -3375);
FORCEPROP 1 LASTPIN (-1225 -3200) $PN 2
J 0
(-1263 -3188);
DISPLAY 0.617021 (-1263 -3188);
PAINT ORANGE (-1263 -3188);
FORCEPROP 1 LASTPIN (-1425 -3200) $PN 1
J 0
(-1413 -3188);
DISPLAY 0.617021 (-1413 -3188);
PAINT ORANGE (-1413 -3188);
FORCEPROP 1 LAST MATERIAL EMPTY
J 0
(-1325 -3350);
DISPLAY 0.617021 (-1325 -3350);
PAINT RED (-1325 -3350);
FORCEPROP 1 LAST TOLERANCE 1%
J 0
(-1325 -3300);
DISPLAY 0.617021 (-1325 -3300);
PAINT SKYBLUE (-1325 -3300);
FORCEPROP 1 LAST VALUE 10.0K
J 2
(-1350 -3300);
DISPLAY 0.617021 (-1350 -3300);
PAINT SKYBLUE (-1350 -3300);
FORCEPROP 1 LAST PACK_TYPE 0402
J 0
(-1200 -3300);
DISPLAY 0.617021 (-1200 -3300);
PAINT SKYBLUE (-1200 -3300);
FORCEPROP 1 LAST WATTAGE 1/16W
J 2
(-1350 -3350);
DISPLAY 0.617021 (-1350 -3350);
PAINT SKYBLUE (-1350 -3350);
FORCEPROP 1 LAST LOCATION R25W67
J 0
(-1400 -3100);
DISPLAY 0.617021 (-1400 -3100);
PAINT AQUA (-1400 -3100);
FORCEPROP 2 LAST CDS_LOCATION R25W67
J 0
(-1200 -3175);
DISPLAY 0.617021 (-1200 -3175);
PAINT AQUA (-1200 -3175);
DISPLAY INVISIBLE (-1200 -3175);
FORCEPROP 0 LAST BOM_COST SM_CONTROLLER
J 0
(-1375 -2900);
DISPLAY 1.021277 (-1375 -2900);
PAINT ORANGE (-1375 -2900);
DISPLAY INVISIBLE (-1375 -2900);
FORCEPROP 2 LAST SEC 1
J 0
(-1375 -3000);
PAINT MONO (-1375 -3000);
DISPLAY INVISIBLE (-1375 -3000);
FORCEPROP 2 LAST SEC_TYPE 0402
J 0
(-1375 -3000);
DISPLAY 1.021277 (-1375 -3000);
PAINT ORANGE (-1375 -3000);
DISPLAY INVISIBLE (-1375 -3000);
FORCEPROP 0 LAST ROOM BMC
J 0
(-1375 -3000);
DISPLAY 1.021277 (-1375 -3000);
PAINT ORANGE (-1375 -3000);
DISPLAY INVISIBLE (-1375 -3000);
FORCEPROP 2 LAST CDS_LIB mstr_discrete
J 0
(-1325 -3200);
PAINT ORANGE (-1325 -3200);
DISPLAY INVISIBLE (-1325 -3200);
FORCEPROP 0 LAST CDS_SEC 1
J 0
(-1200 -3125);
PAINT MONO (-1200 -3125);
DISPLAY INVISIBLE (-1200 -3125);
FORCEPROP 1 LAST PATH I46
J 0
(-1375 -3050);
DISPLAY 0.978723 (-1375 -3050);
PAINT WHITE (-1375 -3050);
DISPLAY INVISIBLE (-1375 -3050);
FORCEADD GND..1
R 1
(-425 -3200);
FORCEPROP 3 LASTPIN (-475 -3200) SIG_NAME GND\g
J 0
(-465 -3190);
DISPLAY 0.659574 (-465 -3190);
PAINT MONO (-465 -3190);
DISPLAY INVISIBLE (-465 -3190);
FORCEPROP 1 LAST HDL_POWER GND
R 1
J 0
(-575 -3200);
DISPLAY 0.872340 (-575 -3200);
PAINT GREEN (-575 -3200);
DISPLAY INVISIBLE (-575 -3200);
FORCEPROP 1 LAST BODY_TYPE PLUMBING
R 1
J 0
(-382 -3245);
DISPLAY 0.340426 (-382 -3245);
PAINT GREEN (-382 -3245);
DISPLAY INVISIBLE (-382 -3245);
FORCEPROP 1 LAST VOLTAGE 0.0V
R 1
J 0
(-382 -3245);
DISPLAY 0.340426 (-382 -3245);
PAINT SKYBLUE (-382 -3245);
DISPLAY INVISIBLE (-382 -3245);
FORCEPROP 2 LAST CDS_LIB mstr_symbols
R 1
J 0
(-425 -3200);
PAINT ORANGE (-425 -3200);
DISPLAY INVISIBLE (-425 -3200);
FORCEPROP 1 LAST SIZE 1B
R 1
J 0
(-375 -3125);
DISPLAY 0.872340 (-375 -3125);
PAINT AQUA (-375 -3125);
DISPLAY INVISIBLE (-375 -3125);
FORCEPROP 1 LAST PATH I47
R 1
J 0
(-425 -3125);
DISPLAY 0.872340 (-425 -3125);
PAINT AQUA (-425 -3125);
DISPLAY INVISIBLE (-425 -3125);
FORCEADD OFFPAGE..4
(-1250 -1300);
FORCEPROP 2 LAST $XR0 158 
J 0
(-1064 -1300);
DISPLAY 0.638298 (-1064 -1300);
PAINT MONO (-1064 -1300);
FORCEPROP 2 LAST $XR1 119 
J 0
(-944 -1300);
DISPLAY 0.638298 (-944 -1300);
PAINT MONO (-944 -1300);
FORCEPROP 1 LAST COMMENT_BODY TRUE
J 0
(-1275 -1400);
DISPLAY 0.872340 (-1275 -1400);
PAINT GREEN (-1275 -1400);
DISPLAY INVISIBLE (-1275 -1400);
FORCEPROP 1 LAST OFFPAGE TRUE
J 0
(-925 -1425);
DISPLAY 0.872340 (-925 -1425);
PAINT GREEN (-925 -1425);
DISPLAY INVISIBLE (-925 -1425);
FORCEPROP 2 LAST PATH I48
J 0
(-925 -1250);
DISPLAY 1.021277 (-925 -1250);
PAINT ORANGE (-925 -1250);
DISPLAY INVISIBLE (-925 -1250);
FORCEPROP 2 LAST CDS_LIB mstr_standard
J 0
(-1250 -1300);
PAINT MONO (-1250 -1300);
DISPLAY INVISIBLE (-1250 -1300);
FORCEADD OFFPAGE..2
(-1250 -1350);
FORCEPROP 2 LAST $XR1 158 
J 0
(-941 -1350);
DISPLAY 0.638298 (-941 -1350);
PAINT MONO (-941 -1350);
FORCEPROP 2 LAST $XR0 119 
J 0
(-1061 -1350);
DISPLAY 0.638298 (-1061 -1350);
PAINT MONO (-1061 -1350);
FORCEPROP 1 LAST COMMENT_BODY TRUE
J 0
(-1295 -1445);
DISPLAY 0.872340 (-1295 -1445);
PAINT GREEN (-1295 -1445);
DISPLAY INVISIBLE (-1295 -1445);
FORCEPROP 1 LAST OFFPAGE TRUE
J 0
(-925 -1475);
DISPLAY 0.872340 (-925 -1475);
PAINT GREEN (-925 -1475);
DISPLAY INVISIBLE (-925 -1475);
FORCEPROP 2 LAST CDS_LIB mstr_standard
J 0
(-1250 -1350);
PAINT MONO (-1250 -1350);
DISPLAY INVISIBLE (-1250 -1350);
FORCEPROP 2 LAST PATH I49
J 0
(-925 -1300);
DISPLAY 1.021277 (-925 -1300);
PAINT ORANGE (-925 -1300);
DISPLAY INVISIBLE (-925 -1300);
FORCEADD OFFPAGE..1
(-6125 -2500);
FORCEPROP 2 LAST $XR0 152 
J 0
(-6377 -2500);
DISPLAY 0.638298 (-6377 -2500);
PAINT MONO (-6377 -2500);
FORCEPROP 1 LAST COMMENT_BODY TRUE
J 0
(-6000 -2600);
DISPLAY 0.872340 (-6000 -2600);
PAINT GREEN (-6000 -2600);
DISPLAY INVISIBLE (-6000 -2600);
FORCEPROP 1 LAST OFFPAGE TRUE
J 0
(-5800 -2625);
DISPLAY 0.872340 (-5800 -2625);
PAINT GREEN (-5800 -2625);
DISPLAY INVISIBLE (-5800 -2625);
FORCEPROP 2 LAST ROOM BMC
J 0
(-6375 -2425);
DISPLAY 1.361702 (-6375 -2425);
PAINT ORANGE (-6375 -2425);
DISPLAY INVISIBLE (-6375 -2425);
FORCEPROP 2 LAST BOM_COST SM_CONTROLLER
J 0
(-5675 -2450);
PAINT MONO (-5675 -2450);
DISPLAY INVISIBLE (-5675 -2450);
FORCEPROP 2 LAST PATH I5
J 0
(-6075 -2425);
DISPLAY 1.021277 (-6075 -2425);
PAINT ORANGE (-6075 -2425);
DISPLAY INVISIBLE (-6075 -2425);
FORCEPROP 2 LAST CDS_LIB mstr_standard
J 0
(-6125 -2500);
PAINT MONO (-6125 -2500);
DISPLAY INVISIBLE (-6125 -2500);
FORCEADD OFFPAGE..2
(-1250 -1800);
FORCEPROP 2 LAST $XR0 183 
J 0
(-1061 -1800);
DISPLAY 0.638298 (-1061 -1800);
PAINT MONO (-1061 -1800);
FORCEPROP 2 LAST $XR1 190 
J 0
(-941 -1800);
DISPLAY 0.638298 (-941 -1800);
PAINT MONO (-941 -1800);
FORCEPROP 2 LAST $XR2 158 
J 0
(-821 -1800);
DISPLAY 0.638298 (-821 -1800);
PAINT MONO (-821 -1800);
FORCEPROP 1 LAST COMMENT_BODY TRUE
J 0
(-1295 -1895);
DISPLAY 0.872340 (-1295 -1895);
PAINT GREEN (-1295 -1895);
DISPLAY INVISIBLE (-1295 -1895);
FORCEPROP 1 LAST OFFPAGE TRUE
J 0
(-925 -1925);
DISPLAY 0.872340 (-925 -1925);
PAINT GREEN (-925 -1925);
DISPLAY INVISIBLE (-925 -1925);
FORCEPROP 2 LAST CDS_LIB mstr_standard
J 0
(-1250 -1800);
PAINT MONO (-1250 -1800);
DISPLAY INVISIBLE (-1250 -1800);
FORCEPROP 2 LAST PATH I51
J 0
(-1075 -1725);
DISPLAY 1.021277 (-1075 -1725);
PAINT ORANGE (-1075 -1725);
DISPLAY INVISIBLE (-1075 -1725);
FORCEADD OFFPAGE..4
(-1250 -1750);
FORCEPROP 2 LAST $XR0 158 
J 0
(-1064 -1750);
DISPLAY 0.638298 (-1064 -1750);
PAINT MONO (-1064 -1750);
FORCEPROP 2 LAST $XR1 183 
J 0
(-944 -1750);
DISPLAY 0.638298 (-944 -1750);
PAINT MONO (-944 -1750);
FORCEPROP 2 LAST $XR2 190 
J 0
(-824 -1750);
DISPLAY 0.638298 (-824 -1750);
PAINT MONO (-824 -1750);
FORCEPROP 1 LAST COMMENT_BODY TRUE
J 0
(-1275 -1850);
DISPLAY 0.872340 (-1275 -1850);
PAINT GREEN (-1275 -1850);
DISPLAY INVISIBLE (-1275 -1850);
FORCEPROP 1 LAST OFFPAGE TRUE
J 0
(-925 -1875);
DISPLAY 0.872340 (-925 -1875);
PAINT GREEN (-925 -1875);
DISPLAY INVISIBLE (-925 -1875);
FORCEPROP 2 LAST PATH I52
J 0
(-1075 -1675);
DISPLAY 1.021277 (-1075 -1675);
PAINT ORANGE (-1075 -1675);
DISPLAY INVISIBLE (-1075 -1675);
FORCEPROP 2 LAST CDS_LIB mstr_standard
J 0
(-1250 -1750);
PAINT MONO (-1250 -1750);
DISPLAY INVISIBLE (-1250 -1750);
FORCEADD OFFPAGE..4
(-1250 -2550);
FORCEPROP 2 LAST $XR2 119 
J 0
(-854 -2550);
DISPLAY 0.638298 (-854 -2550);
PAINT MONO (-854 -2550);
FORCEPROP 2 LAST $XR1 94 
J 0
(-944 -2550);
DISPLAY 0.638298 (-944 -2550);
PAINT MONO (-944 -2550);
FORCEPROP 2 LAST $XR0 215 
J 0
(-1064 -2550);
DISPLAY 0.638298 (-1064 -2550);
PAINT MONO (-1064 -2550);
FORCEPROP 1 LAST COMMENT_BODY TRUE
J 0
(-1275 -2650);
DISPLAY 0.872340 (-1275 -2650);
PAINT GREEN (-1275 -2650);
DISPLAY INVISIBLE (-1275 -2650);
FORCEPROP 1 LAST OFFPAGE TRUE
J 0
(-925 -2675);
DISPLAY 0.872340 (-925 -2675);
PAINT GREEN (-925 -2675);
DISPLAY INVISIBLE (-925 -2675);
FORCEPROP 2 LAST PATH I53
J 0
(-850 -2500);
DISPLAY 1.021277 (-850 -2500);
PAINT ORANGE (-850 -2500);
DISPLAY INVISIBLE (-850 -2500);
FORCEPROP 2 LAST CDS_LIB mstr_standard
J 0
(-1250 -2550);
PAINT MONO (-1250 -2550);
DISPLAY INVISIBLE (-1250 -2550);
FORCEADD OFFPAGE..4
(-1250 -2450);
FORCEPROP 2 LAST $XR1 95 
J 0
(-944 -2450);
DISPLAY 0.638298 (-944 -2450);
PAINT MONO (-944 -2450);
FORCEPROP 2 LAST $XR2 120 
J 0
(-854 -2450);
DISPLAY 0.638298 (-854 -2450);
PAINT MONO (-854 -2450);
FORCEPROP 2 LAST $XR0 201 
J 0
(-1064 -2450);
DISPLAY 0.638298 (-1064 -2450);
PAINT MONO (-1064 -2450);
FORCEPROP 1 LAST COMMENT_BODY TRUE
J 0
(-1275 -2550);
DISPLAY 0.872340 (-1275 -2550);
PAINT GREEN (-1275 -2550);
DISPLAY INVISIBLE (-1275 -2550);
FORCEPROP 1 LAST OFFPAGE TRUE
J 0
(-925 -2575);
DISPLAY 0.872340 (-925 -2575);
PAINT GREEN (-925 -2575);
DISPLAY INVISIBLE (-925 -2575);
FORCEPROP 2 LAST CDS_LIB mstr_standard
J 0
(-1250 -2450);
PAINT MONO (-1250 -2450);
DISPLAY INVISIBLE (-1250 -2450);
FORCEPROP 2 LAST PATH I54
J 0
(-850 -2400);
DISPLAY 1.021277 (-850 -2400);
PAINT ORANGE (-850 -2400);
DISPLAY INVISIBLE (-850 -2400);
FORCEADD OFFPAGE..4
(-1250 -2400);
FORCEPROP 2 LAST $XR1 95 
J 0
(-944 -2400);
DISPLAY 0.638298 (-944 -2400);
PAINT MONO (-944 -2400);
FORCEPROP 2 LAST $XR0 206 
J 0
(-1064 -2400);
DISPLAY 0.638298 (-1064 -2400);
PAINT MONO (-1064 -2400);
FORCEPROP 2 LAST $XR2 120 
J 0
(-854 -2400);
DISPLAY 0.638298 (-854 -2400);
PAINT MONO (-854 -2400);
FORCEPROP 1 LAST COMMENT_BODY TRUE
J 0
(-1275 -2500);
DISPLAY 0.872340 (-1275 -2500);
PAINT GREEN (-1275 -2500);
DISPLAY INVISIBLE (-1275 -2500);
FORCEPROP 1 LAST OFFPAGE TRUE
J 0
(-925 -2525);
DISPLAY 0.872340 (-925 -2525);
PAINT GREEN (-925 -2525);
DISPLAY INVISIBLE (-925 -2525);
FORCEPROP 2 LAST CDS_LIB mstr_standard
J 0
(-1250 -2400);
PAINT MONO (-1250 -2400);
DISPLAY INVISIBLE (-1250 -2400);
FORCEPROP 2 LAST PATH I55
J 0
(-850 -2350);
DISPLAY 1.021277 (-850 -2350);
PAINT ORANGE (-850 -2350);
DISPLAY INVISIBLE (-850 -2350);
FORCEADD OFFPAGE..4
(-1250 -2350);
FORCEPROP 2 LAST $XR0 226 
J 0
(-1064 -2350);
DISPLAY 0.638298 (-1064 -2350);
PAINT MONO (-1064 -2350);
FORCEPROP 2 LAST $XR1 94 
J 0
(-944 -2350);
DISPLAY 0.638298 (-944 -2350);
PAINT MONO (-944 -2350);
FORCEPROP 2 LAST $XR2 119 
J 0
(-854 -2350);
DISPLAY 0.638298 (-854 -2350);
PAINT MONO (-854 -2350);
FORCEPROP 1 LAST COMMENT_BODY TRUE
J 0
(-1275 -2450);
DISPLAY 0.872340 (-1275 -2450);
PAINT GREEN (-1275 -2450);
DISPLAY INVISIBLE (-1275 -2450);
FORCEPROP 1 LAST OFFPAGE TRUE
J 0
(-925 -2475);
DISPLAY 0.872340 (-925 -2475);
PAINT GREEN (-925 -2475);
DISPLAY INVISIBLE (-925 -2475);
FORCEPROP 2 LAST CDS_LIB mstr_standard
J 0
(-1250 -2350);
PAINT MONO (-1250 -2350);
DISPLAY INVISIBLE (-1250 -2350);
FORCEPROP 2 LAST PATH I56
J 0
(-850 -2300);
DISPLAY 1.021277 (-850 -2300);
PAINT ORANGE (-850 -2300);
DISPLAY INVISIBLE (-850 -2300);
FORCEADD OFFPAGE..4
(-1250 -2300);
FORCEPROP 2 LAST $XR0 133 
J 0
(-1064 -2300);
DISPLAY 0.638298 (-1064 -2300);
PAINT MONO (-1064 -2300);
FORCEPROP 2 LAST $XR2 121 
J 0
(-824 -2300);
DISPLAY 0.638298 (-824 -2300);
PAINT MONO (-824 -2300);
FORCEPROP 2 LAST $XR1 187 
J 0
(-944 -2300);
DISPLAY 0.638298 (-944 -2300);
PAINT MONO (-944 -2300);
FORCEPROP 1 LAST COMMENT_BODY TRUE
J 0
(-1275 -2400);
DISPLAY 0.872340 (-1275 -2400);
PAINT GREEN (-1275 -2400);
DISPLAY INVISIBLE (-1275 -2400);
FORCEPROP 1 LAST OFFPAGE TRUE
J 0
(-925 -2425);
DISPLAY 0.872340 (-925 -2425);
PAINT GREEN (-925 -2425);
DISPLAY INVISIBLE (-925 -2425);
FORCEPROP 2 LAST CDS_LIB mstr_standard
J 0
(-1250 -2300);
PAINT MONO (-1250 -2300);
DISPLAY INVISIBLE (-1250 -2300);
FORCEPROP 2 LAST PATH I57
J 0
(-800 -2250);
DISPLAY 1.021277 (-800 -2250);
PAINT ORANGE (-800 -2250);
DISPLAY INVISIBLE (-800 -2250);
FORCEADD OFFPAGE..4
(-1250 -2200);
FORCEPROP 2 LAST $XR2 121 
J 0
(-824 -2200);
DISPLAY 0.638298 (-824 -2200);
PAINT MONO (-824 -2200);
FORCEPROP 2 LAST $XR0 133 
J 0
(-1064 -2200);
DISPLAY 0.638298 (-1064 -2200);
PAINT MONO (-1064 -2200);
FORCEPROP 2 LAST $XR1 188 
J 0
(-944 -2200);
DISPLAY 0.638298 (-944 -2200);
PAINT MONO (-944 -2200);
FORCEPROP 1 LAST COMMENT_BODY TRUE
J 0
(-1275 -2300);
DISPLAY 0.872340 (-1275 -2300);
PAINT GREEN (-1275 -2300);
DISPLAY INVISIBLE (-1275 -2300);
FORCEPROP 1 LAST OFFPAGE TRUE
J 0
(-925 -2325);
DISPLAY 0.872340 (-925 -2325);
PAINT GREEN (-925 -2325);
DISPLAY INVISIBLE (-925 -2325);
FORCEPROP 2 LAST CDS_LIB mstr_standard
J 0
(-1250 -2200);
PAINT MONO (-1250 -2200);
DISPLAY INVISIBLE (-1250 -2200);
FORCEPROP 2 LAST PATH I58
J 0
(-800 -2150);
DISPLAY 1.021277 (-800 -2150);
PAINT ORANGE (-800 -2150);
DISPLAY INVISIBLE (-800 -2150);
FORCEADD OFFPAGE..2
(-1250 -2250);
FORCEPROP 2 LAST $XR1 169 
J 0
(-941 -2250);
DISPLAY 0.638298 (-941 -2250);
PAINT MONO (-941 -2250);
FORCEPROP 2 LAST $XR0 118 
J 0
(-1061 -2250);
DISPLAY 0.638298 (-1061 -2250);
PAINT MONO (-1061 -2250);
FORCEPROP 1 LAST COMMENT_BODY TRUE
J 0
(-1295 -2345);
DISPLAY 0.872340 (-1295 -2345);
PAINT GREEN (-1295 -2345);
DISPLAY INVISIBLE (-1295 -2345);
FORCEPROP 1 LAST OFFPAGE TRUE
J 0
(-925 -2375);
DISPLAY 0.872340 (-925 -2375);
PAINT GREEN (-925 -2375);
DISPLAY INVISIBLE (-925 -2375);
FORCEPROP 2 LAST PATH I59
J 0
(-925 -2200);
DISPLAY 1.021277 (-925 -2200);
PAINT ORANGE (-925 -2200);
DISPLAY INVISIBLE (-925 -2200);
FORCEPROP 2 LAST CDS_LIB mstr_standard
J 0
(-1250 -2250);
PAINT MONO (-1250 -2250);
DISPLAY INVISIBLE (-1250 -2250);
FORCEADD OFFPAGE..1
(-6000 -2800);
FORCEPROP 2 LAST $XR2 249 
J 0
(-6492 -2800);
DISPLAY 0.638298 (-6492 -2800);
PAINT MONO (-6492 -2800);
FORCEPROP 2 LAST $XR0 118 
J 0
(-6252 -2800);
DISPLAY 0.638298 (-6252 -2800);
PAINT MONO (-6252 -2800);
FORCEPROP 2 LAST $XR1 135 
J 0
(-6372 -2800);
DISPLAY 0.638298 (-6372 -2800);
PAINT MONO (-6372 -2800);
FORCEPROP 1 LAST COMMENT_BODY TRUE
J 0
(-5875 -2900);
DISPLAY 0.872340 (-5875 -2900);
PAINT GREEN (-5875 -2900);
DISPLAY INVISIBLE (-5875 -2900);
FORCEPROP 1 LAST OFFPAGE TRUE
J 0
(-5675 -2925);
DISPLAY 0.872340 (-5675 -2925);
PAINT GREEN (-5675 -2925);
DISPLAY INVISIBLE (-5675 -2925);
FORCEPROP 2 LAST CDS_LIB mstr_standard
J 0
(-6000 -2800);
PAINT ORANGE (-6000 -2800);
DISPLAY INVISIBLE (-6000 -2800);
FORCEPROP 2 LAST PATH I6
J 0
(-6250 -2750);
DISPLAY 1.021277 (-6250 -2750);
PAINT ORANGE (-6250 -2750);
DISPLAY INVISIBLE (-6250 -2750);
FORCEADD OFFPAGE..4
(-1250 -3000);
FORCEPROP 2 LAST $XR1 119 
J 0
(-944 -3000);
DISPLAY 0.638298 (-944 -3000);
PAINT MONO (-944 -3000);
FORCEPROP 2 LAST $XR0 175 
J 0
(-1064 -3000);
DISPLAY 0.638298 (-1064 -3000);
PAINT MONO (-1064 -3000);
FORCEPROP 1 LAST COMMENT_BODY TRUE
J 0
(-1275 -3100);
DISPLAY 0.872340 (-1275 -3100);
PAINT GREEN (-1275 -3100);
DISPLAY INVISIBLE (-1275 -3100);
FORCEPROP 1 LAST OFFPAGE TRUE
J 0
(-925 -3125);
DISPLAY 0.872340 (-925 -3125);
PAINT GREEN (-925 -3125);
DISPLAY INVISIBLE (-925 -3125);
FORCEPROP 2 LAST PATH I68
J 0
(-1075 -2925);
DISPLAY 1.021277 (-1075 -2925);
PAINT ORANGE (-1075 -2925);
DISPLAY INVISIBLE (-1075 -2925);
FORCEPROP 2 LAST CDS_LIB mstr_standard
J 0
(-1250 -3000);
PAINT MONO (-1250 -3000);
DISPLAY INVISIBLE (-1250 -3000);
FORCEADD OFFPAGE..4
(-1250 -2900);
FORCEPROP 2 LAST $XR1 119 
J 0
(-944 -2900);
DISPLAY 0.638298 (-944 -2900);
PAINT MONO (-944 -2900);
FORCEPROP 2 LAST $XR2 190 
J 0
(-824 -2900);
DISPLAY 0.638298 (-824 -2900);
PAINT MONO (-824 -2900);
FORCEPROP 2 LAST $XR0 175 
J 0
(-1064 -2900);
DISPLAY 0.638298 (-1064 -2900);
PAINT MONO (-1064 -2900);
FORCEPROP 1 LAST COMMENT_BODY TRUE
J 0
(-1275 -3000);
DISPLAY 0.872340 (-1275 -3000);
PAINT GREEN (-1275 -3000);
DISPLAY INVISIBLE (-1275 -3000);
FORCEPROP 1 LAST OFFPAGE TRUE
J 0
(-925 -3025);
DISPLAY 0.872340 (-925 -3025);
PAINT GREEN (-925 -3025);
DISPLAY INVISIBLE (-925 -3025);
FORCEPROP 2 LAST PATH I69
J 0
(-1075 -2825);
DISPLAY 1.021277 (-1075 -2825);
PAINT ORANGE (-1075 -2825);
DISPLAY INVISIBLE (-1075 -2825);
FORCEPROP 2 LAST CDS_LIB mstr_standard
J 0
(-1250 -2900);
PAINT MONO (-1250 -2900);
DISPLAY INVISIBLE (-1250 -2900);
FORCEADD OFFPAGE..1
(-6000 -2850);
FORCEPROP 2 LAST $XR0 145 
J 0
(-6252 -2850);
DISPLAY 0.638298 (-6252 -2850);
PAINT MONO (-6252 -2850);
FORCEPROP 1 LAST COMMENT_BODY TRUE
J 0
(-5875 -2950);
DISPLAY 0.872340 (-5875 -2950);
PAINT GREEN (-5875 -2950);
DISPLAY INVISIBLE (-5875 -2950);
FORCEPROP 1 LAST OFFPAGE TRUE
J 0
(-5675 -2975);
DISPLAY 0.872340 (-5675 -2975);
PAINT GREEN (-5675 -2975);
DISPLAY INVISIBLE (-5675 -2975);
FORCEPROP 2 LAST PATH I7
J 0
(-6250 -2800);
DISPLAY 1.021277 (-6250 -2800);
PAINT ORANGE (-6250 -2800);
DISPLAY INVISIBLE (-6250 -2800);
FORCEPROP 2 LAST CDS_LIB mstr_standard
J 0
(-6000 -2850);
PAINT ORANGE (-6000 -2850);
DISPLAY INVISIBLE (-6000 -2850);
FORCEADD OFFPAGE..4
(-1250 -2800);
FORCEPROP 2 LAST $XR0 157 
J 0
(-1064 -2800);
DISPLAY 0.638298 (-1064 -2800);
PAINT MONO (-1064 -2800);
FORCEPROP 2 LAST $XR1 119 
J 0
(-944 -2800);
DISPLAY 0.638298 (-944 -2800);
PAINT MONO (-944 -2800);
FORCEPROP 1 LAST COMMENT_BODY TRUE
J 0
(-1275 -2900);
DISPLAY 0.872340 (-1275 -2900);
PAINT GREEN (-1275 -2900);
DISPLAY INVISIBLE (-1275 -2900);
FORCEPROP 1 LAST OFFPAGE TRUE
J 0
(-925 -2925);
DISPLAY 0.872340 (-925 -2925);
PAINT GREEN (-925 -2925);
DISPLAY INVISIBLE (-925 -2925);
FORCEPROP 2 LAST CDS_LIB mstr_standard
J 0
(-1250 -2800);
PAINT MONO (-1250 -2800);
DISPLAY INVISIBLE (-1250 -2800);
FORCEPROP 2 LAST PATH I70
J 0
(-1075 -2725);
DISPLAY 1.021277 (-1075 -2725);
PAINT ORANGE (-1075 -2725);
DISPLAY INVISIBLE (-1075 -2725);
FORCEADD OFFPAGE..4
(-1250 -2700);
FORCEPROP 2 LAST $XR0 93 
J 0
(-1064 -2700);
DISPLAY 0.638298 (-1064 -2700);
PAINT MONO (-1064 -2700);
FORCEPROP 1 LAST COMMENT_BODY TRUE
J 0
(-1275 -2800);
DISPLAY 0.872340 (-1275 -2800);
PAINT GREEN (-1275 -2800);
DISPLAY INVISIBLE (-1275 -2800);
FORCEPROP 1 LAST OFFPAGE TRUE
J 0
(-925 -2825);
DISPLAY 0.872340 (-925 -2825);
PAINT GREEN (-925 -2825);
DISPLAY INVISIBLE (-925 -2825);
FORCEPROP 2 LAST PATH I71
J 0
(-1075 -2625);
DISPLAY 1.021277 (-1075 -2625);
PAINT ORANGE (-1075 -2625);
DISPLAY INVISIBLE (-1075 -2625);
FORCEPROP 2 LAST CDS_LIB mstr_standard
J 0
(-1250 -2700);
PAINT MONO (-1250 -2700);
DISPLAY INVISIBLE (-1250 -2700);
FORCEADD OFFPAGE..4
(-1250 -2650);
FORCEPROP 2 LAST $XR0 93 
J 0
(-1064 -2650);
DISPLAY 0.638298 (-1064 -2650);
PAINT MONO (-1064 -2650);
FORCEPROP 1 LAST COMMENT_BODY TRUE
J 0
(-1275 -2750);
DISPLAY 0.872340 (-1275 -2750);
PAINT GREEN (-1275 -2750);
DISPLAY INVISIBLE (-1275 -2750);
FORCEPROP 1 LAST OFFPAGE TRUE
J 0
(-925 -2775);
DISPLAY 0.872340 (-925 -2775);
PAINT GREEN (-925 -2775);
DISPLAY INVISIBLE (-925 -2775);
FORCEPROP 2 LAST CDS_LIB mstr_standard
J 0
(-1250 -2650);
PAINT MONO (-1250 -2650);
DISPLAY INVISIBLE (-1250 -2650);
FORCEPROP 2 LAST PATH I72
J 0
(-1075 -2575);
DISPLAY 1.021277 (-1075 -2575);
PAINT ORANGE (-1075 -2575);
DISPLAY INVISIBLE (-1075 -2575);
FORCEADD OFFPAGE..2
(-1250 -2950);
FORCEPROP 2 LAST $XR0 156 
J 0
(-1061 -2950);
DISPLAY 0.638298 (-1061 -2950);
PAINT MONO (-1061 -2950);
FORCEPROP 1 LAST COMMENT_BODY TRUE
J 0
(-1295 -3045);
DISPLAY 0.872340 (-1295 -3045);
PAINT GREEN (-1295 -3045);
DISPLAY INVISIBLE (-1295 -3045);
FORCEPROP 1 LAST OFFPAGE TRUE
J 0
(-925 -3075);
DISPLAY 0.872340 (-925 -3075);
PAINT GREEN (-925 -3075);
DISPLAY INVISIBLE (-925 -3075);
FORCEPROP 2 LAST CDS_LIB mstr_standard
J 0
(-1250 -2950);
PAINT MONO (-1250 -2950);
DISPLAY INVISIBLE (-1250 -2950);
FORCEPROP 2 LAST PATH I73
J 0
(-1075 -2875);
DISPLAY 1.021277 (-1075 -2875);
PAINT ORANGE (-1075 -2875);
DISPLAY INVISIBLE (-1075 -2875);
FORCEADD OFFPAGE..2
(-1250 -2850);
FORCEPROP 2 LAST $XR0 156 
J 0
(-1061 -2850);
DISPLAY 0.638298 (-1061 -2850);
PAINT MONO (-1061 -2850);
FORCEPROP 1 LAST COMMENT_BODY TRUE
J 0
(-1295 -2945);
DISPLAY 0.872340 (-1295 -2945);
PAINT GREEN (-1295 -2945);
DISPLAY INVISIBLE (-1295 -2945);
FORCEPROP 1 LAST OFFPAGE TRUE
J 0
(-925 -2975);
DISPLAY 0.872340 (-925 -2975);
PAINT GREEN (-925 -2975);
DISPLAY INVISIBLE (-925 -2975);
FORCEPROP 2 LAST PATH I74
J 0
(-1075 -2775);
DISPLAY 1.021277 (-1075 -2775);
PAINT ORANGE (-1075 -2775);
DISPLAY INVISIBLE (-1075 -2775);
FORCEPROP 2 LAST CDS_LIB mstr_standard
J 0
(-1250 -2850);
PAINT MONO (-1250 -2850);
DISPLAY INVISIBLE (-1250 -2850);
FORCEADD OFFPAGE..2
(-1250 -2750);
FORCEPROP 2 LAST $XR0 120 
J 0
(-1061 -2750);
DISPLAY 0.638298 (-1061 -2750);
PAINT MONO (-1061 -2750);
FORCEPROP 2 LAST $XR1 156 
J 0
(-941 -2750);
DISPLAY 0.638298 (-941 -2750);
PAINT MONO (-941 -2750);
FORCEPROP 1 LAST COMMENT_BODY TRUE
J 0
(-1295 -2845);
DISPLAY 0.872340 (-1295 -2845);
PAINT GREEN (-1295 -2845);
DISPLAY INVISIBLE (-1295 -2845);
FORCEPROP 1 LAST OFFPAGE TRUE
J 0
(-925 -2875);
DISPLAY 0.872340 (-925 -2875);
PAINT GREEN (-925 -2875);
DISPLAY INVISIBLE (-925 -2875);
FORCEPROP 2 LAST CDS_LIB mstr_standard
J 0
(-1250 -2750);
PAINT MONO (-1250 -2750);
DISPLAY INVISIBLE (-1250 -2750);
FORCEPROP 2 LAST PATH I75
J 0
(-1075 -2675);
DISPLAY 1.021277 (-1075 -2675);
PAINT ORANGE (-1075 -2675);
DISPLAY INVISIBLE (-1075 -2675);
FORCEADD OFFPAGE..5
(-6000 -3100);
FORCEPROP 2 LAST $XR1 177 
J 0
(-6375 -3100);
DISPLAY 0.638298 (-6375 -3100);
PAINT MONO (-6375 -3100);
FORCEPROP 2 LAST $XR0 119 
J 0
(-6255 -3100);
DISPLAY 0.638298 (-6255 -3100);
PAINT MONO (-6255 -3100);
FORCEPROP 1 LAST COMMENT_BODY TRUE
J 0
(-5900 -3175);
DISPLAY 0.872340 (-5900 -3175);
PAINT GREEN (-5900 -3175);
DISPLAY INVISIBLE (-5900 -3175);
FORCEPROP 1 LAST OFFPAGE TRUE
J 0
(-5675 -3225);
DISPLAY 0.872340 (-5675 -3225);
PAINT GREEN (-5675 -3225);
DISPLAY INVISIBLE (-5675 -3225);
FORCEPROP 2 LAST CDS_LIB mstr_standard
J 0
(-6000 -3100);
PAINT ORANGE (-6000 -3100);
DISPLAY INVISIBLE (-6000 -3100);
FORCEPROP 2 LAST PATH I76
J 0
(-6250 -3050);
DISPLAY 1.021277 (-6250 -3050);
PAINT ORANGE (-6250 -3050);
DISPLAY INVISIBLE (-6250 -3050);
FORCEADD OFFPAGE..1
(-6000 -2950);
FORCEPROP 2 LAST $XR0 185 
J 0
(-6252 -2950);
DISPLAY 0.638298 (-6252 -2950);
PAINT MONO (-6252 -2950);
FORCEPROP 2 LAST $XR1 120 
J 0
(-6372 -2950);
DISPLAY 0.638298 (-6372 -2950);
PAINT MONO (-6372 -2950);
FORCEPROP 1 LAST COMMENT_BODY TRUE
J 0
(-5875 -3050);
DISPLAY 0.872340 (-5875 -3050);
PAINT GREEN (-5875 -3050);
DISPLAY INVISIBLE (-5875 -3050);
FORCEPROP 1 LAST OFFPAGE TRUE
J 0
(-5675 -3075);
DISPLAY 0.872340 (-5675 -3075);
PAINT GREEN (-5675 -3075);
DISPLAY INVISIBLE (-5675 -3075);
FORCEPROP 2 LAST BOM_COST SM_CONTROLLER
J 0
(-5550 -2900);
PAINT MONO (-5550 -2900);
DISPLAY INVISIBLE (-5550 -2900);
FORCEPROP 2 LAST ROOM BMC
J 0
(-6250 -2875);
DISPLAY 1.361702 (-6250 -2875);
PAINT ORANGE (-6250 -2875);
DISPLAY INVISIBLE (-6250 -2875);
FORCEPROP 2 LAST PATH I78
J 0
(-5950 -2875);
DISPLAY 1.021277 (-5950 -2875);
PAINT ORANGE (-5950 -2875);
DISPLAY INVISIBLE (-5950 -2875);
FORCEPROP 2 LAST CDS_LIB mstr_standard
J 0
(-6000 -2950);
PAINT MONO (-6000 -2950);
DISPLAY INVISIBLE (-6000 -2950);
FORCEADD OFFPAGE..1
(-6125 -1750);
FORCEPROP 2 LAST $XR0 181 
J 0
(-6377 -1750);
DISPLAY 0.638298 (-6377 -1750);
PAINT MONO (-6377 -1750);
FORCEPROP 2 LAST $XR1 119 
J 0
(-6497 -1750);
DISPLAY 0.638298 (-6497 -1750);
PAINT MONO (-6497 -1750);
FORCEPROP 1 LAST COMMENT_BODY TRUE
J 0
(-6000 -1850);
DISPLAY 0.872340 (-6000 -1850);
PAINT GREEN (-6000 -1850);
DISPLAY INVISIBLE (-6000 -1850);
FORCEPROP 1 LAST OFFPAGE TRUE
J 0
(-5800 -1875);
DISPLAY 0.872340 (-5800 -1875);
PAINT GREEN (-5800 -1875);
DISPLAY INVISIBLE (-5800 -1875);
FORCEPROP 2 LAST ROOM BMC
J 0
(-6375 -1675);
DISPLAY 1.361702 (-6375 -1675);
PAINT ORANGE (-6375 -1675);
DISPLAY INVISIBLE (-6375 -1675);
FORCEPROP 2 LAST BOM_COST SM_CONTROLLER
J 0
(-5675 -1700);
PAINT MONO (-5675 -1700);
DISPLAY INVISIBLE (-5675 -1700);
FORCEPROP 2 LAST PATH I79
J 0
(-6075 -1675);
DISPLAY 1.021277 (-6075 -1675);
PAINT ORANGE (-6075 -1675);
DISPLAY INVISIBLE (-6075 -1675);
FORCEPROP 2 LAST CDS_LIB mstr_standard
J 0
(-6125 -1750);
PAINT MONO (-6125 -1750);
DISPLAY INVISIBLE (-6125 -1750);
FORCEADD OSC_C..11
(-6050 -650);
FORCEPROP 1 LAST MATERIAL OSC
J 0
(-6400 -375);
DISPLAY 0.617021 (-6400 -375);
PAINT SKYBLUE (-6400 -375);
FORCEPROP 1 LAST LOCATION Y9F2
J 0
(-6400 -325);
DISPLAY 0.617021 (-6400 -325);
PAINT AQUA (-6400 -325);
FORCEPROP 1 LAST PART_NUMBER D34520-021
J 0
(-6400 -900);
DISPLAY 0.617021 (-6400 -900);
PAINT BLUE (-6400 -900);
FORCEPROP 2 LASTPIN (-5650 -750) $PN 2
J 0
(-5640 -740);
DISPLAY 0.617021 (-5640 -740);
PAINT ORANGE (-5640 -740);
FORCEPROP 2 LASTPIN (-5650 -550) $PN 3
J 0
(-5640 -540);
DISPLAY 0.617021 (-5640 -540);
PAINT ORANGE (-5640 -540);
FORCEPROP 1 LAST VALUE 24MHZ
J 0
(-6400 -425);
DISPLAY 0.617021 (-6400 -425);
PAINT SKYBLUE (-6400 -425);
FORCEPROP 2 LASTPIN (-6450 -550) $PN 4
J 2
(-6460 -540);
DISPLAY 0.617021 (-6460 -540);
PAINT ORANGE (-6460 -540);
FORCEPROP 2 LASTPIN (-6450 -650) $PN 1
J 2
(-6460 -640);
DISPLAY 0.617021 (-6460 -640);
PAINT ORANGE (-6460 -640);
FORCEPROP 0 LAST CDS_SEC 1
J 0
(-6400 -275);
PAINT MONO (-6400 -275);
DISPLAY INVISIBLE (-6400 -275);
FORCEPROP 0 LAST CDS_LOCATION Y9F2
J 0
(-6400 -275);
PAINT MONO (-6400 -275);
DISPLAY INVISIBLE (-6400 -275);
FORCEPROP 1 LAST CDS_LMAN_SYM_OUTLINE -350,200,350,-200
J 0
(-6050 -650);
DISPLAY 0.468085 (-6050 -650);
PAINT GREEN (-6050 -650);
DISPLAY INVISIBLE (-6050 -650);
FORCEPROP 2 LAST CDS_LIB mstr_discrete
J 0
(-6050 -650);
PAINT ORANGE (-6050 -650);
DISPLAY INVISIBLE (-6050 -650);
FORCEPROP 0 LAST ROOM BMC
J 0
(-6400 -225);
DISPLAY 1.021277 (-6400 -225);
PAINT ORANGE (-6400 -225);
DISPLAY INVISIBLE (-6400 -225);
FORCEPROP 2 LAST SEC_TYPE SM4
J 0
(-6400 -275);
DISPLAY 1.021277 (-6400 -275);
PAINT ORANGE (-6400 -275);
DISPLAY INVISIBLE (-6400 -275);
FORCEPROP 0 LAST BOM_COST SM_CONTROLLER
J 0
(-6400 -125);
DISPLAY 1.021277 (-6400 -125);
PAINT ORANGE (-6400 -125);
DISPLAY INVISIBLE (-6400 -125);
FORCEPROP 2 LAST SEC 1
J 0
(-6400 -275);
DISPLAY 0.680851 (-6400 -275);
PAINT MONO (-6400 -275);
DISPLAY INVISIBLE (-6400 -275);
FORCEPROP 1 LAST PACK_TYPE SM4
J 0
(-6400 -275);
PAINT SKYBLUE (-6400 -275);
DISPLAY INVISIBLE (-6400 -275);
FORCEPROP 1 LAST PATH I8
J 0
(-6005 -420);
PAINT GREEN (-6005 -420);
DISPLAY INVISIBLE (-6005 -420);
FORCEADD OFFPAGE..1
(-6125 -1700);
FORCEPROP 2 LAST $XR0 181 
J 0
(-6377 -1700);
DISPLAY 0.638298 (-6377 -1700);
PAINT MONO (-6377 -1700);
FORCEPROP 2 LAST $XR1 119 
J 0
(-6497 -1700);
DISPLAY 0.638298 (-6497 -1700);
PAINT MONO (-6497 -1700);
FORCEPROP 1 LAST COMMENT_BODY TRUE
J 0
(-6000 -1800);
DISPLAY 0.872340 (-6000 -1800);
PAINT GREEN (-6000 -1800);
DISPLAY INVISIBLE (-6000 -1800);
FORCEPROP 1 LAST OFFPAGE TRUE
J 0
(-5800 -1825);
DISPLAY 0.872340 (-5800 -1825);
PAINT GREEN (-5800 -1825);
DISPLAY INVISIBLE (-5800 -1825);
FORCEPROP 2 LAST ROOM BMC
J 0
(-6375 -1625);
DISPLAY 1.361702 (-6375 -1625);
PAINT ORANGE (-6375 -1625);
DISPLAY INVISIBLE (-6375 -1625);
FORCEPROP 2 LAST BOM_COST SM_CONTROLLER
J 0
(-5675 -1650);
PAINT MONO (-5675 -1650);
DISPLAY INVISIBLE (-5675 -1650);
FORCEPROP 2 LAST PATH I80
J 0
(-6075 -1625);
DISPLAY 1.021277 (-6075 -1625);
PAINT ORANGE (-6075 -1625);
DISPLAY INVISIBLE (-6075 -1625);
FORCEPROP 2 LAST CDS_LIB mstr_standard
J 0
(-6125 -1700);
PAINT MONO (-6125 -1700);
DISPLAY INVISIBLE (-6125 -1700);
FORCEADD OFFPAGE..1
(-6125 -1600);
FORCEPROP 2 LAST $XR0 181 
J 0
(-6377 -1600);
DISPLAY 0.638298 (-6377 -1600);
PAINT MONO (-6377 -1600);
FORCEPROP 2 LAST $XR1 119 
J 0
(-6497 -1600);
DISPLAY 0.638298 (-6497 -1600);
PAINT MONO (-6497 -1600);
FORCEPROP 1 LAST COMMENT_BODY TRUE
J 0
(-6000 -1700);
DISPLAY 0.872340 (-6000 -1700);
PAINT GREEN (-6000 -1700);
DISPLAY INVISIBLE (-6000 -1700);
FORCEPROP 1 LAST OFFPAGE TRUE
J 0
(-5800 -1725);
DISPLAY 0.872340 (-5800 -1725);
PAINT GREEN (-5800 -1725);
DISPLAY INVISIBLE (-5800 -1725);
FORCEPROP 2 LAST CDS_LIB mstr_standard
J 0
(-6125 -1600);
PAINT MONO (-6125 -1600);
DISPLAY INVISIBLE (-6125 -1600);
FORCEPROP 2 LAST PATH I81
J 0
(-6075 -1525);
DISPLAY 1.021277 (-6075 -1525);
PAINT ORANGE (-6075 -1525);
DISPLAY INVISIBLE (-6075 -1525);
FORCEPROP 2 LAST BOM_COST SM_CONTROLLER
J 0
(-5675 -1550);
PAINT MONO (-5675 -1550);
DISPLAY INVISIBLE (-5675 -1550);
FORCEPROP 2 LAST ROOM BMC
J 0
(-6375 -1525);
DISPLAY 1.361702 (-6375 -1525);
PAINT ORANGE (-6375 -1525);
DISPLAY INVISIBLE (-6375 -1525);
FORCEADD OFFPAGE..1
(-6125 -1500);
FORCEPROP 2 LAST $XR0 164 
J 0
(-6377 -1500);
DISPLAY 0.638298 (-6377 -1500);
PAINT MONO (-6377 -1500);
FORCEPROP 2 LAST $XR1 119 
J 0
(-6497 -1500);
DISPLAY 0.638298 (-6497 -1500);
PAINT MONO (-6497 -1500);
FORCEPROP 1 LAST COMMENT_BODY TRUE
J 0
(-6000 -1600);
DISPLAY 0.872340 (-6000 -1600);
PAINT GREEN (-6000 -1600);
DISPLAY INVISIBLE (-6000 -1600);
FORCEPROP 1 LAST OFFPAGE TRUE
J 0
(-5800 -1625);
DISPLAY 0.872340 (-5800 -1625);
PAINT GREEN (-5800 -1625);
DISPLAY INVISIBLE (-5800 -1625);
FORCEPROP 2 LAST CDS_LIB mstr_standard
J 0
(-6125 -1500);
PAINT MONO (-6125 -1500);
DISPLAY INVISIBLE (-6125 -1500);
FORCEPROP 2 LAST PATH I82
J 0
(-6075 -1425);
DISPLAY 1.021277 (-6075 -1425);
PAINT ORANGE (-6075 -1425);
DISPLAY INVISIBLE (-6075 -1425);
FORCEPROP 2 LAST ROOM BMC
J 0
(-6375 -1425);
DISPLAY 1.361702 (-6375 -1425);
PAINT ORANGE (-6375 -1425);
DISPLAY INVISIBLE (-6375 -1425);
FORCEPROP 2 LAST BOM_COST SM_CONTROLLER
J 0
(-5675 -1450);
PAINT MONO (-5675 -1450);
DISPLAY INVISIBLE (-5675 -1450);
FORCEADD OFFPAGE..1
(-6125 -1550);
FORCEPROP 2 LAST $XR0 164 
J 0
(-6377 -1550);
DISPLAY 0.638298 (-6377 -1550);
PAINT MONO (-6377 -1550);
FORCEPROP 2 LAST $XR1 119 
J 0
(-6497 -1550);
DISPLAY 0.638298 (-6497 -1550);
PAINT MONO (-6497 -1550);
FORCEPROP 1 LAST COMMENT_BODY TRUE
J 0
(-6000 -1650);
DISPLAY 0.872340 (-6000 -1650);
PAINT GREEN (-6000 -1650);
DISPLAY INVISIBLE (-6000 -1650);
FORCEPROP 1 LAST OFFPAGE TRUE
J 0
(-5800 -1675);
DISPLAY 0.872340 (-5800 -1675);
PAINT GREEN (-5800 -1675);
DISPLAY INVISIBLE (-5800 -1675);
FORCEPROP 2 LAST CDS_LIB mstr_standard
J 0
(-6125 -1550);
PAINT MONO (-6125 -1550);
DISPLAY INVISIBLE (-6125 -1550);
FORCEPROP 2 LAST PATH I83
J 0
(-6075 -1475);
DISPLAY 1.021277 (-6075 -1475);
PAINT ORANGE (-6075 -1475);
DISPLAY INVISIBLE (-6075 -1475);
FORCEPROP 2 LAST ROOM BMC
J 0
(-6375 -1475);
DISPLAY 1.361702 (-6375 -1475);
PAINT ORANGE (-6375 -1475);
DISPLAY INVISIBLE (-6375 -1475);
FORCEPROP 2 LAST BOM_COST SM_CONTROLLER
J 0
(-5675 -1500);
PAINT MONO (-5675 -1500);
DISPLAY INVISIBLE (-5675 -1500);
FORCEADD OFFPAGE..1
(-6125 -1450);
FORCEPROP 2 LAST $XR0 164 
J 0
(-6377 -1450);
DISPLAY 0.638298 (-6377 -1450);
PAINT MONO (-6377 -1450);
FORCEPROP 2 LAST $XR1 119 
J 0
(-6497 -1450);
DISPLAY 0.638298 (-6497 -1450);
PAINT MONO (-6497 -1450);
FORCEPROP 1 LAST COMMENT_BODY TRUE
J 0
(-6000 -1550);
DISPLAY 0.872340 (-6000 -1550);
PAINT GREEN (-6000 -1550);
DISPLAY INVISIBLE (-6000 -1550);
FORCEPROP 1 LAST OFFPAGE TRUE
J 0
(-5800 -1575);
DISPLAY 0.872340 (-5800 -1575);
PAINT GREEN (-5800 -1575);
DISPLAY INVISIBLE (-5800 -1575);
FORCEPROP 2 LAST CDS_LIB mstr_standard
J 0
(-6125 -1450);
PAINT MONO (-6125 -1450);
DISPLAY INVISIBLE (-6125 -1450);
FORCEPROP 2 LAST PATH I84
J 0
(-6075 -1375);
DISPLAY 1.021277 (-6075 -1375);
PAINT ORANGE (-6075 -1375);
DISPLAY INVISIBLE (-6075 -1375);
FORCEPROP 2 LAST ROOM BMC
J 0
(-6375 -1375);
DISPLAY 1.361702 (-6375 -1375);
PAINT ORANGE (-6375 -1375);
DISPLAY INVISIBLE (-6375 -1375);
FORCEPROP 2 LAST BOM_COST SM_CONTROLLER
J 0
(-5675 -1400);
PAINT MONO (-5675 -1400);
DISPLAY INVISIBLE (-5675 -1400);
FORCEADD OFFPAGE..1
(-6125 -1350);
FORCEPROP 2 LAST $XR0 93 
J 0
(-6346 -1350);
DISPLAY 0.638298 (-6346 -1350);
PAINT MONO (-6346 -1350);
FORCEPROP 1 LAST COMMENT_BODY TRUE
J 0
(-6000 -1450);
DISPLAY 0.872340 (-6000 -1450);
PAINT GREEN (-6000 -1450);
DISPLAY INVISIBLE (-6000 -1450);
FORCEPROP 1 LAST OFFPAGE TRUE
J 0
(-5800 -1475);
DISPLAY 0.872340 (-5800 -1475);
PAINT GREEN (-5800 -1475);
DISPLAY INVISIBLE (-5800 -1475);
FORCEPROP 2 LAST PATH I85
J 0
(-6325 -1300);
DISPLAY 1.021277 (-6325 -1300);
PAINT ORANGE (-6325 -1300);
DISPLAY INVISIBLE (-6325 -1300);
FORCEPROP 2 LAST BOM_COST SM_CONTROLLER
J 0
(-5675 -1300);
PAINT MONO (-5675 -1300);
DISPLAY INVISIBLE (-5675 -1300);
FORCEPROP 2 LAST ROOM BMC
J 0
(-6375 -1275);
DISPLAY 1.361702 (-6375 -1275);
PAINT ORANGE (-6375 -1275);
DISPLAY INVISIBLE (-6375 -1275);
FORCEPROP 2 LAST CDS_LIB mstr_standard
J 2
(-6125 -1350);
PAINT ORANGE (-6125 -1350);
DISPLAY INVISIBLE (-6125 -1350);
FORCEADD OFFPAGE..1
(-6125 -1300);
FORCEPROP 2 LAST $XR0 93 
J 0
(-6346 -1300);
DISPLAY 0.638298 (-6346 -1300);
PAINT MONO (-6346 -1300);
FORCEPROP 1 LAST COMMENT_BODY TRUE
J 0
(-6000 -1400);
DISPLAY 0.872340 (-6000 -1400);
PAINT GREEN (-6000 -1400);
DISPLAY INVISIBLE (-6000 -1400);
FORCEPROP 1 LAST OFFPAGE TRUE
J 0
(-5800 -1425);
DISPLAY 0.872340 (-5800 -1425);
PAINT GREEN (-5800 -1425);
DISPLAY INVISIBLE (-5800 -1425);
FORCEPROP 2 LAST PATH I86
J 0
(-6325 -1250);
DISPLAY 1.021277 (-6325 -1250);
PAINT ORANGE (-6325 -1250);
DISPLAY INVISIBLE (-6325 -1250);
FORCEPROP 2 LAST BOM_COST SM_CONTROLLER
J 0
(-5675 -1250);
PAINT MONO (-5675 -1250);
DISPLAY INVISIBLE (-5675 -1250);
FORCEPROP 2 LAST ROOM BMC
J 0
(-6375 -1225);
DISPLAY 1.361702 (-6375 -1225);
PAINT ORANGE (-6375 -1225);
DISPLAY INVISIBLE (-6375 -1225);
FORCEPROP 2 LAST CDS_LIB mstr_standard
J 2
(-6125 -1300);
PAINT ORANGE (-6125 -1300);
DISPLAY INVISIBLE (-6125 -1300);
FORCEADD OFFPAGE..4
(-1250 -2050);
FORCEPROP 2 LAST $XR1 120 
J 0
(-944 -2050);
DISPLAY 0.638298 (-944 -2050);
PAINT MONO (-944 -2050);
FORCEPROP 2 LAST $XR0 200 
J 0
(-1064 -2050);
DISPLAY 0.638298 (-1064 -2050);
PAINT MONO (-1064 -2050);
FORCEPROP 1 LAST COMMENT_BODY TRUE
J 0
(-1275 -2150);
DISPLAY 0.872340 (-1275 -2150);
PAINT GREEN (-1275 -2150);
DISPLAY INVISIBLE (-1275 -2150);
FORCEPROP 1 LAST OFFPAGE TRUE
J 0
(-925 -2175);
DISPLAY 0.872340 (-925 -2175);
PAINT GREEN (-925 -2175);
DISPLAY INVISIBLE (-925 -2175);
FORCEPROP 2 LAST CDS_LIB mstr_standard
J 0
(-1250 -2050);
PAINT ORANGE (-1250 -2050);
DISPLAY INVISIBLE (-1250 -2050);
FORCEPROP 2 LAST PATH I87
J 0
(-925 -2000);
DISPLAY 1.021277 (-925 -2000);
PAINT ORANGE (-925 -2000);
DISPLAY INVISIBLE (-925 -2000);
FORCEADD OFFPAGE..4
(-1250 -2000);
FORCEPROP 2 LAST $XR2 170 
J 0
(-824 -2000);
DISPLAY 0.638298 (-824 -2000);
PAINT MONO (-824 -2000);
FORCEPROP 2 LAST $XR1 120 
J 0
(-944 -2000);
DISPLAY 0.638298 (-944 -2000);
PAINT MONO (-944 -2000);
FORCEPROP 2 LAST $XR0 200 
J 0
(-1064 -2000);
DISPLAY 0.638298 (-1064 -2000);
PAINT MONO (-1064 -2000);
FORCEPROP 1 LAST COMMENT_BODY TRUE
J 0
(-1275 -2100);
DISPLAY 0.872340 (-1275 -2100);
PAINT GREEN (-1275 -2100);
DISPLAY INVISIBLE (-1275 -2100);
FORCEPROP 1 LAST OFFPAGE TRUE
J 0
(-925 -2125);
DISPLAY 0.872340 (-925 -2125);
PAINT GREEN (-925 -2125);
DISPLAY INVISIBLE (-925 -2125);
FORCEPROP 2 LAST CDS_LIB mstr_standard
J 0
(-1250 -2000);
PAINT ORANGE (-1250 -2000);
DISPLAY INVISIBLE (-1250 -2000);
FORCEPROP 2 LAST PATH I88
J 0
(-800 -1950);
DISPLAY 1.021277 (-800 -1950);
PAINT ORANGE (-800 -1950);
DISPLAY INVISIBLE (-800 -1950);
FORCEADD OFFPAGE..4
(-1250 -2100);
FORCEPROP 2 LAST $XR2 170 
J 0
(-824 -2100);
DISPLAY 0.638298 (-824 -2100);
PAINT MONO (-824 -2100);
FORCEPROP 2 LAST $XR0 200 
J 0
(-1064 -2100);
DISPLAY 0.638298 (-1064 -2100);
PAINT MONO (-1064 -2100);
FORCEPROP 2 LAST $XR1 120 
J 0
(-944 -2100);
DISPLAY 0.638298 (-944 -2100);
PAINT MONO (-944 -2100);
FORCEPROP 1 LAST COMMENT_BODY TRUE
J 0
(-1275 -2200);
DISPLAY 0.872340 (-1275 -2200);
PAINT GREEN (-1275 -2200);
DISPLAY INVISIBLE (-1275 -2200);
FORCEPROP 1 LAST OFFPAGE TRUE
J 0
(-925 -2225);
DISPLAY 0.872340 (-925 -2225);
PAINT GREEN (-925 -2225);
DISPLAY INVISIBLE (-925 -2225);
FORCEPROP 2 LAST CDS_LIB mstr_standard
J 0
(-1250 -2100);
PAINT ORANGE (-1250 -2100);
DISPLAY INVISIBLE (-1250 -2100);
FORCEPROP 2 LAST PATH I89
J 0
(-800 -2050);
DISPLAY 1.021277 (-800 -2050);
PAINT ORANGE (-800 -2050);
DISPLAY INVISIBLE (-800 -2050);
FORCEADD OFFPAGE..2
(-3550 -550);
FORCEPROP 2 LAST $XR0 145 
J 0
(-3361 -550);
DISPLAY 0.638298 (-3361 -550);
PAINT MONO (-3361 -550);
FORCEPROP 1 LAST COMMENT_BODY TRUE
J 0
(-3595 -645);
DISPLAY 0.872340 (-3595 -645);
PAINT GREEN (-3595 -645);
DISPLAY INVISIBLE (-3595 -645);
FORCEPROP 1 LAST OFFPAGE TRUE
J 0
(-3225 -675);
DISPLAY 0.872340 (-3225 -675);
PAINT GREEN (-3225 -675);
DISPLAY INVISIBLE (-3225 -675);
FORCEPROP 2 LAST CDS_LIB mstr_standard
J 0
(-3550 -550);
PAINT ORANGE (-3550 -550);
DISPLAY INVISIBLE (-3550 -550);
FORCEPROP 2 LAST PATH I9
J 0
(-3350 -500);
DISPLAY 1.021277 (-3350 -500);
PAINT ORANGE (-3350 -500);
DISPLAY INVISIBLE (-3350 -500);
FORCEADD OFFPAGE..2
(-1250 -1950);
FORCEPROP 2 LAST $XR0 120 
J 0
(-1061 -1950);
DISPLAY 0.638298 (-1061 -1950);
PAINT MONO (-1061 -1950);
FORCEPROP 2 LAST $XR1 136 
J 0
(-941 -1950);
DISPLAY 0.638298 (-941 -1950);
PAINT MONO (-941 -1950);
FORCEPROP 2 LAST $XR2 157 
J 0
(-821 -1950);
DISPLAY 0.638298 (-821 -1950);
PAINT MONO (-821 -1950);
FORCEPROP 1 LAST COMMENT_BODY TRUE
J 0
(-1295 -2045);
DISPLAY 0.872340 (-1295 -2045);
PAINT GREEN (-1295 -2045);
DISPLAY INVISIBLE (-1295 -2045);
FORCEPROP 1 LAST OFFPAGE TRUE
J 0
(-925 -2075);
DISPLAY 0.872340 (-925 -2075);
PAINT GREEN (-925 -2075);
DISPLAY INVISIBLE (-925 -2075);
FORCEPROP 2 LAST CDS_LIB mstr_standard
J 0
(-1250 -1950);
PAINT ORANGE (-1250 -1950);
DISPLAY INVISIBLE (-1250 -1950);
FORCEPROP 2 LAST PATH I90
J 0
(-800 -1900);
DISPLAY 1.021277 (-800 -1900);
PAINT ORANGE (-800 -1900);
DISPLAY INVISIBLE (-800 -1900);
FORCEADD OFFPAGE..4
(-1250 -1900);
FORCEPROP 2 LAST $XR1 120 
J 0
(-944 -1900);
DISPLAY 0.638298 (-944 -1900);
PAINT MONO (-944 -1900);
FORCEPROP 2 LAST $XR0 191 
J 0
(-1064 -1900);
DISPLAY 0.638298 (-1064 -1900);
PAINT MONO (-1064 -1900);
FORCEPROP 1 LAST COMMENT_BODY TRUE
J 0
(-1275 -2000);
DISPLAY 0.872340 (-1275 -2000);
PAINT GREEN (-1275 -2000);
DISPLAY INVISIBLE (-1275 -2000);
FORCEPROP 1 LAST OFFPAGE TRUE
J 0
(-925 -2025);
DISPLAY 0.872340 (-925 -2025);
PAINT GREEN (-925 -2025);
DISPLAY INVISIBLE (-925 -2025);
FORCEPROP 2 LAST CDS_LIB mstr_standard
J 0
(-1250 -1900);
PAINT ORANGE (-1250 -1900);
DISPLAY INVISIBLE (-1250 -1900);
FORCEPROP 2 LAST PATH I91
J 0
(-925 -1850);
DISPLAY 1.021277 (-925 -1850);
PAINT ORANGE (-925 -1850);
DISPLAY INVISIBLE (-925 -1850);
FORCEADD OFFPAGE..2
(-1250 -1850);
FORCEPROP 2 LAST $XR1 170 
J 0
(-941 -1850);
DISPLAY 0.638298 (-941 -1850);
PAINT MONO (-941 -1850);
FORCEPROP 2 LAST $XR0 119 
J 0
(-1061 -1850);
DISPLAY 0.638298 (-1061 -1850);
PAINT MONO (-1061 -1850);
FORCEPROP 1 LAST COMMENT_BODY TRUE
J 0
(-1295 -1945);
DISPLAY 0.872340 (-1295 -1945);
PAINT GREEN (-1295 -1945);
DISPLAY INVISIBLE (-1295 -1945);
FORCEPROP 1 LAST OFFPAGE TRUE
J 0
(-925 -1975);
DISPLAY 0.872340 (-925 -1975);
PAINT GREEN (-925 -1975);
DISPLAY INVISIBLE (-925 -1975);
FORCEPROP 2 LAST CDS_LIB mstr_standard
J 0
(-1250 -1850);
PAINT ORANGE (-1250 -1850);
DISPLAY INVISIBLE (-1250 -1850);
FORCEPROP 2 LAST PATH I92
J 0
(-925 -1800);
DISPLAY 1.021277 (-925 -1800);
PAINT ORANGE (-925 -1800);
DISPLAY INVISIBLE (-925 -1800);
FORCEADD OFFPAGE..4
(-1250 -1600);
FORCEPROP 2 LAST $XR1 133 
J 0
(-974 -1600);
DISPLAY 0.638298 (-974 -1600);
PAINT MONO (-974 -1600);
FORCEPROP 2 LAST $XR2 120 
J 0
(-854 -1600);
DISPLAY 0.638298 (-854 -1600);
PAINT MONO (-854 -1600);
FORCEPROP 2 LAST $XR0 56 
J 0
(-1064 -1600);
DISPLAY 0.638298 (-1064 -1600);
PAINT MONO (-1064 -1600);
FORCEPROP 1 LAST COMMENT_BODY TRUE
J 0
(-1275 -1700);
DISPLAY 0.872340 (-1275 -1700);
PAINT GREEN (-1275 -1700);
DISPLAY INVISIBLE (-1275 -1700);
FORCEPROP 1 LAST OFFPAGE TRUE
J 0
(-925 -1725);
DISPLAY 0.872340 (-925 -1725);
PAINT GREEN (-925 -1725);
DISPLAY INVISIBLE (-925 -1725);
FORCEPROP 2 LAST PATH I93
J 0
(-850 -1550);
DISPLAY 1.021277 (-850 -1550);
PAINT ORANGE (-850 -1550);
DISPLAY INVISIBLE (-850 -1550);
FORCEPROP 2 LAST CDS_LIB mstr_standard
J 0
(-1250 -1600);
PAINT ORANGE (-1250 -1600);
DISPLAY INVISIBLE (-1250 -1600);
FORCEADD OFFPAGE..4
(-1250 -1650);
FORCEPROP 2 LAST $XR2 118 
J 0
(-854 -1650);
DISPLAY 0.638298 (-854 -1650);
PAINT MONO (-854 -1650);
FORCEPROP 2 LAST $XR3 120 
J 0
(-734 -1650);
DISPLAY 0.638298 (-734 -1650);
PAINT MONO (-734 -1650);
FORCEPROP 2 LAST $XR1 133 
J 0
(-974 -1650);
DISPLAY 0.638298 (-974 -1650);
PAINT MONO (-974 -1650);
FORCEPROP 2 LAST $XR0 22 
J 0
(-1064 -1650);
DISPLAY 0.638298 (-1064 -1650);
PAINT MONO (-1064 -1650);
FORCEPROP 1 LAST COMMENT_BODY TRUE
J 0
(-1275 -1750);
DISPLAY 0.872340 (-1275 -1750);
PAINT GREEN (-1275 -1750);
DISPLAY INVISIBLE (-1275 -1750);
FORCEPROP 1 LAST OFFPAGE TRUE
J 0
(-925 -1775);
DISPLAY 0.872340 (-925 -1775);
PAINT GREEN (-925 -1775);
DISPLAY INVISIBLE (-925 -1775);
FORCEPROP 2 LAST CDS_LIB mstr_standard
J 0
(-1250 -1650);
PAINT ORANGE (-1250 -1650);
DISPLAY INVISIBLE (-1250 -1650);
FORCEPROP 2 LAST PATH I94
J 0
(-725 -1600);
DISPLAY 1.021277 (-725 -1600);
PAINT ORANGE (-725 -1600);
DISPLAY INVISIBLE (-725 -1600);
FORCEADD OFFPAGE..2
(-1250 -1500);
FORCEPROP 2 LAST $XR1 126 
J 0
(-941 -1500);
DISPLAY 0.638298 (-941 -1500);
PAINT MONO (-941 -1500);
FORCEPROP 2 LAST $XR2 200 
J 0
(-821 -1500);
DISPLAY 0.638298 (-821 -1500);
PAINT MONO (-821 -1500);
FORCEPROP 2 LAST $XR0 120 
J 0
(-1061 -1500);
DISPLAY 0.638298 (-1061 -1500);
PAINT MONO (-1061 -1500);
FORCEPROP 1 LAST COMMENT_BODY TRUE
J 0
(-1295 -1595);
DISPLAY 0.872340 (-1295 -1595);
PAINT GREEN (-1295 -1595);
DISPLAY INVISIBLE (-1295 -1595);
FORCEPROP 1 LAST OFFPAGE TRUE
J 0
(-925 -1625);
DISPLAY 0.872340 (-925 -1625);
PAINT GREEN (-925 -1625);
DISPLAY INVISIBLE (-925 -1625);
FORCEPROP 2 LAST CDS_LIB mstr_standard
J 0
(-1250 -1500);
PAINT ORANGE (-1250 -1500);
DISPLAY INVISIBLE (-1250 -1500);
FORCEPROP 2 LAST PATH I95
J 0
(-800 -1450);
DISPLAY 1.021277 (-800 -1450);
PAINT ORANGE (-800 -1450);
DISPLAY INVISIBLE (-800 -1450);
FORCEADD OFFPAGE..2
(-1250 -1550);
FORCEPROP 2 LAST $XR1 133 
J 0
(-941 -1550);
DISPLAY 0.638298 (-941 -1550);
PAINT MONO (-941 -1550);
FORCEPROP 2 LAST $XR2 182 
J 0
(-821 -1550);
DISPLAY 0.638298 (-821 -1550);
PAINT MONO (-821 -1550);
FORCEPROP 2 LAST $XR0 120 
J 0
(-1061 -1550);
DISPLAY 0.638298 (-1061 -1550);
PAINT MONO (-1061 -1550);
FORCEPROP 1 LAST COMMENT_BODY TRUE
J 0
(-1295 -1645);
DISPLAY 0.872340 (-1295 -1645);
PAINT GREEN (-1295 -1645);
DISPLAY INVISIBLE (-1295 -1645);
FORCEPROP 1 LAST OFFPAGE TRUE
J 0
(-925 -1675);
DISPLAY 0.872340 (-925 -1675);
PAINT GREEN (-925 -1675);
DISPLAY INVISIBLE (-925 -1675);
FORCEPROP 2 LAST PATH I96
J 0
(-800 -1500);
DISPLAY 1.021277 (-800 -1500);
PAINT ORANGE (-800 -1500);
DISPLAY INVISIBLE (-800 -1500);
FORCEPROP 2 LAST CDS_LIB mstr_standard
J 0
(-1250 -1550);
PAINT ORANGE (-1250 -1550);
DISPLAY INVISIBLE (-1250 -1550);
FORCEADD OFFPAGE..2
(-1250 -1450);
FORCEPROP 2 LAST $XR1 182 
J 0
(-941 -1450);
DISPLAY 0.638298 (-941 -1450);
PAINT MONO (-941 -1450);
FORCEPROP 2 LAST $XR0 119 
J 0
(-1061 -1450);
DISPLAY 0.638298 (-1061 -1450);
PAINT MONO (-1061 -1450);
FORCEPROP 1 LAST COMMENT_BODY TRUE
J 0
(-1295 -1545);
DISPLAY 0.872340 (-1295 -1545);
PAINT GREEN (-1295 -1545);
DISPLAY INVISIBLE (-1295 -1545);
FORCEPROP 1 LAST OFFPAGE TRUE
J 0
(-925 -1575);
DISPLAY 0.872340 (-925 -1575);
PAINT GREEN (-925 -1575);
DISPLAY INVISIBLE (-925 -1575);
FORCEPROP 2 LAST CDS_LIB mstr_standard
J 0
(-1250 -1450);
PAINT ORANGE (-1250 -1450);
DISPLAY INVISIBLE (-1250 -1450);
FORCEPROP 2 LAST PATH I97
J 0
(-925 -1400);
DISPLAY 1.021277 (-925 -1400);
PAINT ORANGE (-925 -1400);
DISPLAY INVISIBLE (-925 -1400);
FORCEADD OFFPAGE..2
(-1250 -1400);
FORCEPROP 2 LAST $XR1 157 
J 0
(-941 -1400);
DISPLAY 0.638298 (-941 -1400);
PAINT MONO (-941 -1400);
FORCEPROP 2 LAST $XR2 190 
J 0
(-821 -1400);
DISPLAY 0.638298 (-821 -1400);
PAINT MONO (-821 -1400);
FORCEPROP 2 LAST $XR0 118 
J 0
(-1061 -1400);
DISPLAY 0.638298 (-1061 -1400);
PAINT MONO (-1061 -1400);
FORCEPROP 1 LAST COMMENT_BODY TRUE
J 0
(-1295 -1495);
DISPLAY 0.872340 (-1295 -1495);
PAINT GREEN (-1295 -1495);
DISPLAY INVISIBLE (-1295 -1495);
FORCEPROP 1 LAST OFFPAGE TRUE
J 0
(-925 -1525);
DISPLAY 0.872340 (-925 -1525);
PAINT GREEN (-925 -1525);
DISPLAY INVISIBLE (-925 -1525);
FORCEPROP 2 LAST CDS_LIB mstr_standard
J 0
(-1250 -1400);
PAINT ORANGE (-1250 -1400);
DISPLAY INVISIBLE (-1250 -1400);
FORCEPROP 2 LAST PATH I98
J 0
(-800 -1350);
DISPLAY 1.021277 (-800 -1350);
PAINT ORANGE (-800 -1350);
DISPLAY INVISIBLE (-800 -1350);
FORCEADD OFFPAGE..6
(-6000 -2700);
FORCEPROP 2 LAST $XR0 145 
J 0
(-6280 -2700);
DISPLAY 0.638298 (-6280 -2700);
PAINT MONO (-6280 -2700);
FORCEPROP 1 LAST COMMENT_BODY TRUE
J 0
(-5900 -2775);
DISPLAY 0.872340 (-5900 -2775);
PAINT GREEN (-5900 -2775);
DISPLAY INVISIBLE (-5900 -2775);
FORCEPROP 1 LAST OFFPAGE TRUE
J 0
(-5675 -2825);
DISPLAY 0.872340 (-5675 -2825);
PAINT GREEN (-5675 -2825);
DISPLAY INVISIBLE (-5675 -2825);
FORCEPROP 2 LAST PATH I99
J 0
(-6275 -2650);
DISPLAY 1.021277 (-6275 -2650);
PAINT ORANGE (-6275 -2650);
DISPLAY INVISIBLE (-6275 -2650);
FORCEPROP 2 LAST $XRERR ?
J 0
(-6424 -2700);
DISPLAY 0.638298 (-6424 -2700);
PAINT MONO (-6424 -2700);
DISPLAY INVISIBLE (-6424 -2700);
FORCEPROP 2 LAST $XRERR ?
J 0
(-6424 -2700);
DISPLAY 0.638298 (-6424 -2700);
PAINT MONO (-6424 -2700);
DISPLAY INVISIBLE (-6424 -2700);
FORCEPROP 2 LAST $XRERR ?
J 0
(-6424 -2700);
DISPLAY 0.638298 (-6424 -2700);
PAINT MONO (-6424 -2700);
DISPLAY INVISIBLE (-6424 -2700);
FORCEPROP 2 LAST $XRERR ?
J 0
(-6424 -2700);
DISPLAY 0.638298 (-6424 -2700);
PAINT MONO (-6424 -2700);
DISPLAY INVISIBLE (-6424 -2700);
FORCEPROP 2 LAST $XRERR ?
J 0
(-6424 -2700);
DISPLAY 0.638298 (-6424 -2700);
PAINT MONO (-6424 -2700);
DISPLAY INVISIBLE (-6424 -2700);
FORCEPROP 2 LAST $XRERR ?
J 0
(-6424 -2700);
DISPLAY 0.638298 (-6424 -2700);
PAINT MONO (-6424 -2700);
DISPLAY INVISIBLE (-6424 -2700);
FORCEPROP 2 LAST $XRERR ?
J 0
(-6424 -2700);
DISPLAY 0.638298 (-6424 -2700);
PAINT MONO (-6424 -2700);
DISPLAY INVISIBLE (-6424 -2700);
FORCEPROP 2 LAST $XRERR ?
J 0
(-6424 -2700);
DISPLAY 0.638298 (-6424 -2700);
PAINT MONO (-6424 -2700);
DISPLAY INVISIBLE (-6424 -2700);
FORCEPROP 2 LAST $XRERR ?
J 0
(-6424 -2700);
DISPLAY 0.638298 (-6424 -2700);
PAINT MONO (-6424 -2700);
DISPLAY INVISIBLE (-6424 -2700);
FORCEPROP 2 LAST $XRERR ?
J 0
(-6424 -2700);
DISPLAY 0.638298 (-6424 -2700);
PAINT MONO (-6424 -2700);
DISPLAY INVISIBLE (-6424 -2700);
FORCEPROP 2 LAST $XRERR ?
J 0
(-6424 -2700);
DISPLAY 0.638298 (-6424 -2700);
PAINT MONO (-6424 -2700);
DISPLAY INVISIBLE (-6424 -2700);
FORCEPROP 2 LAST CDS_LIB mstr_standard
J 0
(-6000 -2700);
PAINT ORANGE (-6000 -2700);
DISPLAY INVISIBLE (-6000 -2700);
FORCEADD INTEL_CORP_BPAGE..1
(-225 -5000);
FORCEPROP 1 LAST CDS_CON_LAST_MODIFIED Tue Dec 01 11:52:04 2015
J 0
(-1650 -4675);
DISPLAY 1.361702 (-1650 -4675);
PAINT GREEN (-1650 -4675);
DISPLAY INVISIBLE (-1650 -4675);
FORCEPROP 1 LAST CUSTOM_TXT_CDS <CURRENT_DESIGN_SHEET> OF <TOTAL_DESIGN_SHEETS>
J 0
(-725 -4975);
PAINT GREEN (-725 -4975);
FORCEPROP 1 LAST CUSTOM_TXT_CDS <CON_LAST_MODIFIED>
J 0
(-2150 -4650);
PAINT GREEN (-2150 -4650);
FORCEPROP 2 LAST CUSTOM_TXT_CDS <XR_PAGE_TITLE>
J 0
(-8115 250);
DISPLAY 0.638298 (-8115 250);
PAINT PINK (-8115 250);
DISPLAY INVISIBLE (-8115 250);
FORCEPROP 1 LAST SCH_DEPT BESD
J 1
(-4675 -4900);
DISPLAY 1.212766 (-4675 -4900);
PAINT YELLOW (-4675 -4900);
FORCEPROP 1 LAST SCH_ADDRESS3 Santa Clara, CA 95052-8119
J 0
(-4200 -4975);
DISPLAY 0.617021 (-4200 -4975);
PAINT GREEN (-4200 -4975);
FORCEPROP 1 LAST SCH_TITLE BMC (3 OF 7)
J 0
(-8175 -4950);
DISPLAY 1.212766 (-8175 -4950);
PAINT ORANGE (-8175 -4950);
FORCEPROP 1 LAST SCH_ADDRESS2 P.O. BOX 58119
J 0
(-4200 -4925);
DISPLAY 0.617021 (-4200 -4925);
PAINT GREEN (-4200 -4925);
FORCEPROP 1 LAST SCH_REV 2.420
J 0
(-475 -4850);
DISPLAY 0.978723 (-475 -4850);
PAINT YELLOW (-475 -4850);
FORCEPROP 1 LAST SCH_ADDRESS1 2200 Mission College Blvd.
J 0
(-4200 -4875);
DISPLAY 0.617021 (-4200 -4875);
PAINT GREEN (-4200 -4875);
FORCEPROP 1 LAST SCH_NUMBER H4694802
J 0
(-1525 -4850);
DISPLAY 1.212766 (-1525 -4850);
PAINT YELLOW (-1525 -4850);
FORCEPROP 1 LAST COMMENT_BODY TRUE
J 0
(-213 -4988);
DISPLAY 0.617021 (-213 -4988);
PAINT GREEN (-213 -4988);
DISPLAY INVISIBLE (-213 -4988);
FORCEPROP 2 LAST PAGE_BORDER TRUE
J 0
(-8115 250);
DISPLAY 0.851064 (-8115 250);
PAINT PINK (-8115 250);
DISPLAY INVISIBLE (-8115 250);
FORCEPROP 2 LAST CDS_LIB mstr_symbols
J 0
(-225 -5000);
DISPLAY 1.361702 (-225 -5000);
PAINT ORANGE (-225 -5000);
DISPLAY INVISIBLE (-225 -5000);
FORCEPROP 2 LAST CDS_XR_PAGE_TITLE CR-145 : @BASEBOARD_FAB2_LIB.BASEBOARD_FAB2(SCH_1):PAGE145
J 0
(-8115 250);
DISPLAY 0.638298 (-8115 250);
PAINT PINK (-8115 250);
DISPLAY INVISIBLE (-8115 250);
FORCEADD CAD_NOTE..1
(-7975 -725);
FORCEPROP 0 LAST L1 PLACE 0.1UF CAP CLOSE TO OSC
J 0
(-8125 -850);
DISPLAY 1.021277 (-8125 -850);
PAINT ORANGE (-8125 -850);
FORCEPROP 0 LAST L2 VDD PIN
J 0
(-8125 -925);
DISPLAY 1.021277 (-8125 -925);
PAINT ORANGE (-8125 -925);
FORCEPROP 1 LAST COMMENT_BODY TRUE
J 0
(-7950 -625);
DISPLAY 0.978723 (-7950 -625);
PAINT ORANGE (-7950 -625);
DISPLAY INVISIBLE (-7950 -625);
FORCEPROP 2 LAST CDS_LIB mstr_symbols
J 0
(-7975 -725);
PAINT ORANGE (-7975 -725);
DISPLAY INVISIBLE (-7975 -725);
FORCEADD DNS..2
(-7445 -2430);
PAINT RED (-7445 -2430);
FORCEPROP 1 LAST COMMENT_BODY TRUE
R 1
J 0
(-7370 -2655);
DISPLAY 0.872340 (-7370 -2655);
PAINT GREEN (-7370 -2655);
DISPLAY INVISIBLE (-7370 -2655);
FORCEPROP 2 LAST CDS_LIB mstr_misc
J 0
(-7445 -2430);
PAINT MONO (-7445 -2430);
DISPLAY INVISIBLE (-7445 -2430);
FORCEADD DNS..2
(-1645 -3430);
PAINT RED (-1645 -3430);
FORCEPROP 1 LAST COMMENT_BODY TRUE
R 1
J 0
(-1570 -3655);
DISPLAY 0.872340 (-1570 -3655);
PAINT GREEN (-1570 -3655);
DISPLAY INVISIBLE (-1570 -3655);
FORCEPROP 2 LAST CDS_LIB mstr_misc
J 0
(-1645 -3430);
PAINT ORANGE (-1645 -3430);
DISPLAY INVISIBLE (-1645 -3430);
FORCEADD DNS..2
(-4745 -255);
PAINT RED (-4745 -255);
FORCEPROP 1 LAST COMMENT_BODY TRUE
R 1
J 0
(-4670 -480);
DISPLAY 0.872340 (-4670 -480);
PAINT GREEN (-4670 -480);
DISPLAY INVISIBLE (-4670 -480);
FORCEPROP 2 LAST CDS_LIB mstr_misc
J 0
(-4745 -255);
PAINT ORANGE (-4745 -255);
DISPLAY INVISIBLE (-4745 -255);
FORCEADD DNS..2
(-7020 -2680);
PAINT RED (-7020 -2680);
FORCEPROP 1 LAST COMMENT_BODY TRUE
R 1
J 0
(-6945 -2905);
DISPLAY 0.872340 (-6945 -2905);
PAINT GREEN (-6945 -2905);
DISPLAY INVISIBLE (-6945 -2905);
FORCEPROP 2 LAST CDS_LIB mstr_misc
J 0
(-7020 -2680);
PAINT MONO (-7020 -2680);
DISPLAY INVISIBLE (-7020 -2680);
FORCEADD CAD_NOTE..1
(-3925 -175);
FORCEPROP 0 LAST L1 USE SHARED PADS
J 0
(-4075 -300);
DISPLAY 0.808511 (-4075 -300);
PAINT ORANGE (-4075 -300);
FORCEPROP 1 LAST COMMENT_BODY TRUE
J 0
(-3900 -75);
DISPLAY 0.978723 (-3900 -75);
PAINT ORANGE (-3900 -75);
DISPLAY INVISIBLE (-3900 -75);
FORCEPROP 2 LAST CDS_LIB mstr_symbols
J 0
(-3925 -175);
PAINT ORANGE (-3925 -175);
DISPLAY INVISIBLE (-3925 -175);
FORCEADD DNS..2
(-1320 -3205);
PAINT RED (-1320 -3205);
FORCEPROP 1 LAST COMMENT_BODY TRUE
R 1
J 0
(-1245 -3430);
DISPLAY 0.872340 (-1245 -3430);
PAINT GREEN (-1245 -3430);
DISPLAY INVISIBLE (-1245 -3430);
FORCEPROP 2 LAST CDS_LIB mstr_misc
J 0
(-1320 -3205);
PAINT ORANGE (-1320 -3205);
DISPLAY INVISIBLE (-1320 -3205);
FORCEADD DNS..2
(-1270 -3705);
PAINT RED (-1270 -3705);
FORCEPROP 1 LAST COMMENT_BODY TRUE
R 1
J 0
(-1195 -3930);
DISPLAY 0.872340 (-1195 -3930);
PAINT GREEN (-1195 -3930);
DISPLAY INVISIBLE (-1195 -3930);
FORCEPROP 2 LAST CDS_LIB mstr_misc
J 0
(-1270 -3705);
PAINT ORANGE (-1270 -3705);
DISPLAY INVISIBLE (-1270 -3705);
FORCEADD DNS..2
(-7470 -3580);
PAINT RED (-7470 -3580);
FORCEPROP 1 LAST COMMENT_BODY TRUE
R 1
J 0
(-7395 -3805);
DISPLAY 0.872340 (-7395 -3805);
PAINT GREEN (-7395 -3805);
DISPLAY INVISIBLE (-7395 -3805);
FORCEPROP 2 LAST CDS_LIB mstr_misc
J 0
(-7470 -3580);
PAINT ORANGE (-7470 -3580);
DISPLAY INVISIBLE (-7470 -3580);
WIRE 16 -1 (-7000 -2750)(-7000 -3125);
WIRE 16 -1 (-5575 -825)(-5575 -750);
WIRE 16 -1 (-5575 -750)(-5650 -750);
WIRE 16 -1 (-6450 -550)(-6550 -550);
WIRE 16 -1 (-6550 -550)(-6550 -300);
WIRE 16 -1 (-6550 -300)(-7000 -300);
WIRE 16 -1 (-7000 -300)(-7000 -375);
WIRE 16 -1 (-7000 -300)(-7500 -300);
WIRE 16 -1 (-7500 -350)(-7500 -300);
WIRE 16 -1 (-7500 -300)(-7500 -250);
WIRE 16 -1 (-7500 -550)(-7500 -625);
WIRE 16 -1 (-7475 -3675)(-7475 -3800);
WIRE 16 -1 (-5200 -4450)(-5200 -4650);
WIRE 16 -1 (-5450 -4450)(-5450 -4650);
WIRE 16 -1 (-5700 -4450)(-5700 -4650);
WIRE 16 -1 (-5950 -4425)(-5950 -4650);
WIRE 16 -1 (-6200 -4425)(-6200 -4650);
WIRE 16 -1 (-475 -3200)(-1225 -3200);
WIRE 16 -1 (-1375 -3700)(-2400 -3700);
FORCEPROP 2 LAST SIG_NAME P2E_SSB_BMC_RX_DN
J 0
(-2135 -3690);
DISPLAY 0.680851 (-2135 -3690);
PAINT ORANGE (-2135 -3690);
FORCEPROP 2 LASTPROP $XRERR UNIQUE?
J 0
(-2375 -3690);
DISPLAY 0.638298 (-2375 -3690);
PAINT MONO (-2375 -3690);
DISPLAY INVISIBLE (-2375 -3690);
WIRE 16 -1 (-2400 -3350)(-2400 -3700);
WIRE 16 -1 (-2500 -3350)(-2400 -3350);
WIRE 16 -1 (-2500 -2950)(-1300 -2950);
FORCEPROP 0 LAST SIG_NAME RST_BMC_SYSRST_BTN_OUT_N
J 0
(-2200 -2940);
DISPLAY 0.680851 (-2200 -2940);
PAINT ORANGE (-2200 -2940);
WIRE 16 -1 (-2500 -2900)(-1300 -2900);
FORCEPROP 0 LAST SIG_NAME FM_PWR_BTN_N
J 0
(-2200 -2890);
DISPLAY 0.680851 (-2200 -2890);
PAINT ORANGE (-2200 -2890);
WIRE 16 -1 (-2500 -2850)(-1300 -2850);
FORCEPROP 0 LAST SIG_NAME FM_BMC_PWRBTN_OUT_N
J 0
(-2200 -2840);
DISPLAY 0.680851 (-2200 -2840);
PAINT ORANGE (-2200 -2840);
WIRE 16 -1 (-2500 -2800)(-1300 -2800);
FORCEPROP 0 LAST SIG_NAME FP_NMI_BTN_N
J 0
(-2200 -2790);
DISPLAY 0.680851 (-2200 -2790);
PAINT ORANGE (-2200 -2790);
WIRE 16 -1 (-2500 -2750)(-1300 -2750);
FORCEPROP 0 LAST SIG_NAME IRQ_BMC_PCH_NMI_STBY_N
J 0
(-2175 -2740);
DISPLAY 0.680851 (-2175 -2740);
PAINT ORANGE (-2175 -2740);
WIRE 16 -1 (-2500 -2700)(-1300 -2700);
FORCEPROP 2 LAST SIG_NAME FM_CPU0_PROCHOT_LVT3_BMC_N
J 0
(-2175 -2690);
DISPLAY 0.680851 (-2175 -2690);
PAINT ORANGE (-2175 -2690);
WIRE 16 -1 (-2500 -2100)(-1300 -2100);
FORCEPROP 2 LAST SIG_NAME IRQ_UV_DETECT_N
J 2
(-1750 -2090);
DISPLAY 0.680851 (-1750 -2090);
PAINT ORANGE (-1750 -2090);
WIRE 16 -1 (-6075 -1450)(-5100 -1450);
FORCEPROP 2 LAST SIG_NAME FM_BOARD_REV_ID2
J 2
(-5575 -1440);
DISPLAY 0.617021 (-5575 -1440);
PAINT ORANGE (-5575 -1440);
WIRE 16 -1 (-6075 -1350)(-5100 -1350);
FORCEPROP 0 LAST SIG_NAME FM_CPU_ERR0_LVT3_BMC_N
J 0
(-5925 -1340);
DISPLAY 0.617021 (-5925 -1340);
PAINT ORANGE (-5925 -1340);
WIRE 16 -1 (-2500 -1800)(-1300 -1800);
FORCEPROP 2 LAST SIG_NAME SP1_BMC_HOST_UART_TX
J 2
(-1650 -1790);
DISPLAY 0.680851 (-1650 -1790);
PAINT ORANGE (-1650 -1790);
WIRE 16 -1 (-2500 -2250)(-1300 -2250);
FORCEPROP 0 LAST SIG_NAME FM_BATTERY_SENSE_EN_N
J 0
(-2150 -2240);
DISPLAY 0.680851 (-2150 -2240);
PAINT ORANGE (-2150 -2240);
WIRE 16 -1 (-2500 -2350)(-1300 -2350);
FORCEPROP 0 LAST SIG_NAME IRQ_PVDDQ_KLM_VRHOT_LVT3_N
J 0
(-2150 -2340);
DISPLAY 0.680851 (-2150 -2340);
PAINT ORANGE (-2150 -2340);
WIRE 16 -1 (-2500 -2400)(-1300 -2400);
FORCEPROP 2 LAST SIG_NAME IRQ_PVCCIN_CPU1_VRHOT_LVC3_N
J 0
(-2150 -2390);
DISPLAY 0.680851 (-2150 -2390);
PAINT ORANGE (-2150 -2390);
WIRE 16 -1 (-6100 -2000)(-5100 -2000);
FORCEPROP 0 LAST SIG_NAME SMB_LAN_STBY_LVC3_SDA_R
J 0
(-5935 -1990);
DISPLAY 0.680851 (-5935 -1990);
PAINT ORANGE (-5935 -1990);
WIRE 16 -1 (-5100 -1850)(-6075 -1850);
FORCEPROP 2 LAST SIG_NAME SMB_IE_3V3AUX_SDA
J 0
(-5935 -1840);
DISPLAY 0.680851 (-5935 -1840);
PAINT ORANGE (-5935 -1840);
WIRE 16 -1 (-6075 -1300)(-5100 -1300);
FORCEPROP 0 LAST SIG_NAME FM_CPU_ERR1_LVT3_BMC_N
J 0
(-5925 -1290);
DISPLAY 0.617021 (-5925 -1290);
PAINT ORANGE (-5925 -1290);
WIRE 16 -1 (-6075 -1600)(-5100 -1600);
FORCEPROP 2 LAST SIG_NAME FM_MB_SLOT_ID2
J 0
(-5925 -1590);
DISPLAY 0.617021 (-5925 -1590);
PAINT ORANGE (-5925 -1590);
WIRE 16 -1 (-6075 -1750)(-5100 -1750);
FORCEPROP 2 LAST SIG_NAME FM_MB_SLOT_ID0
J 0
(-5925 -1740);
DISPLAY 0.617021 (-5925 -1740);
PAINT ORANGE (-5925 -1740);
WIRE 16 -1 (-2500 -3000)(-1300 -3000);
FORCEPROP 0 LAST SIG_NAME RST_SYSTEM_BTN_N
J 0
(-2175 -2990);
DISPLAY 0.680851 (-2175 -2990);
PAINT ORANGE (-2175 -2990);
WIRE 16 -1 (-2500 -3200)(-1425 -3200);
FORCEPROP 2 LAST SIG_NAME PD_PEREXT
J 2
(-1525 -3190);
DISPLAY 0.680851 (-1525 -3190);
PAINT ORANGE (-1525 -3190);
FORCEPROP 2 LASTPROP $XRERR UNIQUE?
J 0
(-1765 -3190);
DISPLAY 0.638298 (-1765 -3190);
PAINT MONO (-1765 -3190);
DISPLAY INVISIBLE (-1765 -3190);
WIRE 16 -1 (-2500 -3100)(-1775 -3100);
FORCEPROP 2 LAST SIG_NAME UART_BMC_TXD5
J 0
(-2385 -3090);
DISPLAY 0.680851 (-2385 -3090);
PAINT ORANGE (-2385 -3090);
WIRE 16 -1 (-2500 -2650)(-1300 -2650);
FORCEPROP 2 LAST SIG_NAME FM_CPU1_PROCHOT_LVT3_BMC_N
J 0
(-2175 -2640);
DISPLAY 0.680851 (-2175 -2640);
PAINT ORANGE (-2175 -2640);
WIRE 16 -1 (-2500 -2450)(-1300 -2450);
FORCEPROP 2 LAST SIG_NAME IRQ_PVCCIN_CPU0_VRHOT_LVC3_N
J 0
(-2150 -2440);
DISPLAY 0.680851 (-2150 -2440);
PAINT ORANGE (-2150 -2440);
WIRE 16 -1 (-2500 -2550)(-1300 -2550);
FORCEPROP 0 LAST SIG_NAME IRQ_PVDDQ_ABC_VRHOT_LVT3_N
J 0
(-2175 -2540);
DISPLAY 0.680851 (-2175 -2540);
PAINT ORANGE (-2175 -2540);
WIRE 16 -1 (-2500 -1750)(-1300 -1750);
FORCEPROP 2 LAST SIG_NAME SP1_BMC_HOST_UART_RX
J 2
(-1650 -1740);
DISPLAY 0.680851 (-1650 -1740);
PAINT ORANGE (-1650 -1740);
WIRE 16 -1 (-2500 -1850)(-1300 -1850);
FORCEPROP 2 LAST SIG_NAME FM_PMBUS_ALERT_BUF_EN_N
J 2
(-1575 -1840);
DISPLAY 0.680851 (-1575 -1840);
PAINT ORANGE (-1575 -1840);
WIRE 16 -1 (-2500 -2050)(-1300 -2050);
FORCEPROP 2 LAST SIG_NAME IRQ_OC_DETECT_N
J 2
(-1750 -2040);
DISPLAY 0.680851 (-1750 -2040);
PAINT ORANGE (-1750 -2040);
WIRE 16 -1 (-2500 -1300)(-1300 -1300);
FORCEPROP 2 LAST SIG_NAME SP2_BMC_CM_UART_RX
J 2
(-1700 -1290);
DISPLAY 0.680851 (-1700 -1290);
PAINT ORANGE (-1700 -1290);
WIRE 16 -1 (-2500 -1350)(-1300 -1350);
FORCEPROP 2 LAST SIG_NAME SP2_BMC_CM_UART_TX
J 2
(-1700 -1340);
DISPLAY 0.680851 (-1700 -1340);
PAINT ORANGE (-1700 -1340);
WIRE 16 -1 (-2500 -1400)(-1300 -1400);
FORCEPROP 2 LAST SIG_NAME FM_BMC_CPLD_MP_RST_N
J 2
(-1650 -1390);
DISPLAY 0.680851 (-1650 -1390);
PAINT ORANGE (-1650 -1390);
WIRE 16 -1 (-2500 -1450)(-1300 -1450);
FORCEPROP 2 LAST SIG_NAME FM_BB_BMC_MP_GPIO
J 2
(-1725 -1440);
DISPLAY 0.680851 (-1725 -1440);
PAINT ORANGE (-1725 -1440);
WIRE 16 -1 (-2500 -1500)(-1300 -1500);
FORCEPROP 0 LAST CDS_PHYS_NET_NAME FM_OC_DETECT_EN_N
J 0
(-1300 -1461);
PAINT MONO (-1300 -1461);
DISPLAY INVISIBLE (-1300 -1461);
FORCEPROP 0 LAST PHYS_NET_NAME FM_OC_DETECT_EN_N
J 0
(-1300 -1414);
PAINT MONO (-1300 -1414);
DISPLAY INVISIBLE (-1300 -1414);
FORCEPROP 2 LAST SIG_NAME FM_OC_DETECT_EN_N
J 2
(-1725 -1490);
DISPLAY 0.680851 (-1725 -1490);
PAINT ORANGE (-1725 -1490);
WIRE 16 -1 (-2500 -1550)(-1300 -1550);
FORCEPROP 0 LAST CDS_PHYS_NET_NAME IRQ_BOARD_BMC_ALERT_N
J 0
(-1300 -1511);
PAINT MONO (-1300 -1511);
DISPLAY INVISIBLE (-1300 -1511);
FORCEPROP 0 LAST PHYS_NET_NAME IRQ_BOARD_BMC_ALERT_N
J 0
(-1300 -1464);
PAINT MONO (-1300 -1464);
DISPLAY INVISIBLE (-1300 -1464);
FORCEPROP 2 LAST SIG_NAME IRQ_BOARD_BMC_ALERT_N
J 2
(-1625 -1540);
DISPLAY 0.680851 (-1625 -1540);
PAINT ORANGE (-1625 -1540);
WIRE 16 -1 (-2500 -1600)(-1300 -1600);
FORCEPROP 0 LAST CDS_PHYS_NET_NAME FM_CPU1_RC_ERROR_N
J 0
(-1300 -1561);
PAINT MONO (-1300 -1561);
DISPLAY INVISIBLE (-1300 -1561);
FORCEPROP 0 LAST PHYS_NET_NAME FM_CPU1_RC_ERROR_N
J 0
(-1300 -1514);
PAINT MONO (-1300 -1514);
DISPLAY INVISIBLE (-1300 -1514);
FORCEPROP 2 LAST SIG_NAME FM_CPU1_RC_ERROR_N
J 2
(-1700 -1590);
DISPLAY 0.680851 (-1700 -1590);
PAINT ORANGE (-1700 -1590);
WIRE 16 -1 (-2500 -1650)(-1300 -1650);
FORCEPROP 2 LAST SIG_NAME FM_CPU0_RC_ERROR_N
J 2
(-1700 -1640);
DISPLAY 0.680851 (-1700 -1640);
PAINT ORANGE (-1700 -1640);
WIRE 16 -1 (-5950 -3700)(-5100 -3700);
WIRE 16 -1 (-6600 -3700)(-5950 -3700);
FORCEPROP 2 LAST SIG_NAME P2E_SSB_BMC_TX_C_DP
J 0
(-6610 -3690);
DISPLAY 0.617021 (-6610 -3690);
PAINT ORANGE (-6610 -3690);
WIRE 16 -1 (-5950 -3700)(-5950 -4225);
WIRE 16 -1 (-5100 -3750)(-6200 -3750);
WIRE 16 -1 (-6200 -3750)(-6600 -3750);
FORCEPROP 2 LAST SIG_NAME P2E_SSB_BMC_TX_C_DN
J 0
(-6610 -3740);
DISPLAY 0.617021 (-6610 -3740);
PAINT ORANGE (-6610 -3740);
WIRE 16 -1 (-6200 -4225)(-6200 -3750);
WIRE 16 -1 (-5200 -3450)(-5100 -3450);
WIRE 16 -1 (-6600 -3450)(-5200 -3450);
FORCEPROP 2 LAST SIG_NAME RST_PLTRST_BUF_N
J 0
(-6610 -3440);
DISPLAY 0.617021 (-6610 -3440);
PAINT ORANGE (-6610 -3440);
WIRE 16 -1 (-5200 -4250)(-5200 -3450);
WIRE 16 -1 (-5950 -2950)(-5100 -2950);
FORCEPROP 0 LAST SIG_NAME FM_SSATA_PCIE_M2_SEL
J 0
(-5925 -2940);
DISPLAY 0.680851 (-5925 -2940);
PAINT ORANGE (-5925 -2940);
WIRE 16 -1 (-5950 -2800)(-5100 -2800);
FORCEPROP 2 LAST SIG_NAME RST_BMC_SRST_N
J 0
(-5885 -2790);
DISPLAY 0.680851 (-5885 -2790);
PAINT ORANGE (-5885 -2790);
WIRE 16 -1 (-5950 -2850)(-5100 -2850);
FORCEPROP 2 LAST SIG_NAME CLK_24M_25M_BMC_CLKIN
J 2
(-5385 -2840);
DISPLAY 0.680851 (-5385 -2840);
PAINT ORANGE (-5385 -2840);
WIRE 16 -1 (-6075 -1700)(-5100 -1700);
FORCEPROP 2 LAST SIG_NAME FM_MB_SLOT_ID1
J 0
(-5925 -1690);
DISPLAY 0.617021 (-5925 -1690);
PAINT ORANGE (-5925 -1690);
WIRE 16 -1 (-6075 -1500)(-5100 -1500);
FORCEPROP 2 LAST SIG_NAME FM_BOARD_REV_ID1
J 2
(-5575 -1490);
DISPLAY 0.617021 (-5575 -1490);
PAINT ORANGE (-5575 -1490);
WIRE 16 -1 (-6075 -1550)(-5100 -1550);
FORCEPROP 2 LAST SIG_NAME FM_BOARD_REV_ID0
J 2
(-5575 -1540);
DISPLAY 0.617021 (-5575 -1540);
PAINT ORANGE (-5575 -1540);
WIRE 16 -1 (-5825 -3250)(-5100 -3250);
FORCEPROP 2 LAST SIG_NAME PECI_BMC_R
J 0
(-5510 -3240);
DISPLAY 0.617021 (-5510 -3240);
PAINT ORANGE (-5510 -3240);
FORCEPROP 2 LASTPROP $XRERR UNIQUE?
J 0
(-5750 -3240);
DISPLAY 0.638298 (-5750 -3240);
PAINT MONO (-5750 -3240);
DISPLAY INVISIBLE (-5750 -3240);
WIRE 16 -1 (-5850 -3350)(-5100 -3350);
FORCEPROP 2 LAST SIG_NAME UART_BMC_RXD5
J 0
(-5860 -3340);
DISPLAY 0.617021 (-5860 -3340);
PAINT ORANGE (-5860 -3340);
WIRE 16 -1 (-5450 -3550)(-5100 -3550);
WIRE 16 -1 (-6600 -3550)(-5450 -3550);
FORCEPROP 2 LAST SIG_NAME CLK_100M_BMC_PE_R_DP
J 0
(-6610 -3540);
DISPLAY 0.617021 (-6610 -3540);
PAINT ORANGE (-6610 -3540);
WIRE 16 -1 (-5450 -4250)(-5450 -3550);
WIRE 16 -1 (-5100 -3600)(-5700 -3600);
WIRE 16 -1 (-5700 -3600)(-6600 -3600);
FORCEPROP 2 LAST SIG_NAME CLK_100M_BMC_PE_R_DN
J 0
(-6610 -3590);
DISPLAY 0.617021 (-6610 -3590);
PAINT ORANGE (-6610 -3590);
WIRE 16 -1 (-5700 -3600)(-5700 -4250);
WIRE 16 -1 (-2500 -1900)(-1300 -1900);
FORCEPROP 2 LAST SIG_NAME FM_MEM_THERM_EVENT_PCH_N
J 2
(-1525 -1890);
DISPLAY 0.680851 (-1525 -1890);
PAINT ORANGE (-1525 -1890);
WIRE 16 -1 (-2500 -1950)(-1300 -1950);
FORCEPROP 2 LAST SIG_NAME FM_BIOS_TOP_SWAP
J 2
(-1775 -1940);
DISPLAY 0.680851 (-1775 -1940);
PAINT ORANGE (-1775 -1940);
WIRE 16 -1 (-2500 -2000)(-1300 -2000);
FORCEPROP 2 LAST SIG_NAME FM_HSC_TIMER_EXP_N
J 2
(-1725 -1990);
DISPLAY 0.680851 (-1725 -1990);
PAINT ORANGE (-1725 -1990);
WIRE 16 -1 (-2500 -2200)(-1300 -2200);
FORCEPROP 2 LAST SIG_NAME FM_OCP_MEZZC_PRES_N
J 0
(-2135 -2190);
DISPLAY 0.680851 (-2135 -2190);
PAINT ORANGE (-2135 -2190);
WIRE 16 -1 (-2500 -2300)(-1300 -2300);
FORCEPROP 2 LAST SIG_NAME FM_OCP_MEZZB_PRES_N
J 0
(-2135 -2290);
DISPLAY 0.680851 (-2135 -2290);
PAINT ORANGE (-2135 -2290);
WIRE 16 -1 (-5100 -3000)(-5950 -3000);
FORCEPROP 2 LAST SIG_NAME FM_OCP_MEZZA_PRES_N
J 0
(-5935 -2990);
DISPLAY 0.680851 (-5935 -2990);
PAINT ORANGE (-5935 -2990);
WIRE 16 -1 (-6075 -2450)(-5100 -2450);
FORCEPROP 2 LAST SIG_NAME FM_BIOS_SMI_ACTIVE_N
J 0
(-5925 -2440);
DISPLAY 0.617021 (-5925 -2440);
PAINT ORANGE (-5925 -2440);
WIRE 16 -1 (-6125 -2050)(-5100 -2050);
FORCEPROP 0 LAST SIG_NAME SMB_LAN_STBY_LVC3_SCL_R
J 0
(-5935 -2040);
DISPLAY 0.680851 (-5935 -2040);
PAINT ORANGE (-5935 -2040);
WIRE 16 -1 (-5100 -1900)(-6100 -1900);
FORCEPROP 2 LAST SIG_NAME SMB_IE_3V3AUX_SCL
J 0
(-5935 -1890);
DISPLAY 0.680851 (-5935 -1890);
PAINT ORANGE (-5935 -1890);
WIRE 16 -1 (-6075 -2500)(-5100 -2500);
FORCEPROP 0 LAST SIG_NAME H_CPU1_MEMGHJ_MEMHOT_LVT3_BMC_N
J 0
(-6075 -2490);
DISPLAY 0.617021 (-6075 -2490);
PAINT ORANGE (-6075 -2490);
WIRE 16 -1 (-5950 -2700)(-5100 -2700);
FORCEPROP 2 LAST SIG_NAME FM_BMC_ONCTL_R_N
J 0
(-5935 -2690);
DISPLAY 0.680851 (-5935 -2690);
PAINT ORANGE (-5935 -2690);
WIRE 16 -1 (-5950 -3100)(-5100 -3100);
FORCEPROP 2 LAST SIG_NAME FM_BMC_FAULT_LED_N
J 0
(-5935 -3090);
DISPLAY 0.617021 (-5935 -3090);
PAINT ORANGE (-5935 -3090);
WIRE 16 -1 (-5950 -3150)(-5100 -3150);
FORCEPROP 2 LAST SIG_NAME FM_BMC_HEARTBEAT_N
J 0
(-5925 -3140);
DISPLAY 0.617021 (-5925 -3140);
PAINT ORANGE (-5925 -3140);
WIRE 16 -1 (-5100 -2350)(-6100 -2350);
FORCEPROP 2 LAST SIG_NAME SMB_PCIE_SSD_3V3AUX_SCL
J 0
(-5935 -2340);
DISPLAY 0.680851 (-5935 -2340);
PAINT ORANGE (-5935 -2340);
WIRE 16 -1 (-5100 -2300)(-6075 -2300);
FORCEPROP 2 LAST SIG_NAME SMB_PCIE_SSD_3V3AUX_SDA
J 0
(-5935 -2290);
DISPLAY 0.680851 (-5935 -2290);
PAINT ORANGE (-5935 -2290);
WIRE 16 -1 (-2500 -3300)(-2325 -3300);
WIRE 16 -1 (-2325 -3300)(-2325 -3400);
WIRE 16 -1 (-1750 -3400)(-2325 -3400);
FORCEPROP 2 LAST SIG_NAME P2E_SSB_BMC_RX_DP
J 0
(-2135 -3390);
DISPLAY 0.680851 (-2135 -3390);
PAINT ORANGE (-2135 -3390);
FORCEPROP 2 LASTPROP $XRERR UNIQUE?
J 0
(-2375 -3390);
DISPLAY 0.638298 (-2375 -3390);
PAINT MONO (-2375 -3390);
DISPLAY INVISIBLE (-2375 -3390);
WIRE 16 -1 (-5100 -2150)(-5950 -2150);
FORCEPROP 2 LAST SIG_NAME TP_SMB_BUS11_SDA
J 0
(-5910 -2140);
DISPLAY 0.680851 (-5910 -2140);
PAINT ORANGE (-5910 -2140);
FORCEPROP 2 LASTPROP $XRERR UNIQUE?
J 0
(-6190 -2150);
DISPLAY 0.638298 (-6190 -2150);
PAINT MONO (-6190 -2150);
DISPLAY INVISIBLE (-6190 -2150);
WIRE 16 -1 (-5950 -2200)(-5100 -2200);
FORCEPROP 2 LAST SIG_NAME TP_SMB_BUS11_SCL
J 0
(-5910 -2190);
DISPLAY 0.680851 (-5910 -2190);
PAINT ORANGE (-5910 -2190);
FORCEPROP 2 LASTPROP $XRERR UNIQUE?
J 0
(-6190 -2200);
DISPLAY 0.638298 (-6190 -2200);
PAINT MONO (-6190 -2200);
DISPLAY INVISIBLE (-6190 -2200);
WIRE 16 -1 (-6025 -3250)(-7475 -3250);
FORCEPROP 2 LAST SIG_NAME PECI_BMC
J 0
(-7335 -3240);
DISPLAY 0.617021 (-7335 -3240);
PAINT ORANGE (-7335 -3240);
WIRE 16 -1 (-7475 -3475)(-7475 -3250);
WIRE 16 -1 (-7700 -3250)(-7475 -3250);
WIRE 16 -1 (-7000 -2400)(-6600 -2400);
FORCEPROP 2 LAST SIG_NAME FM_BMC_ONCTL_R_N
J 0
(-6985 -2390);
DISPLAY 0.617021 (-6985 -2390);
PAINT ORANGE (-6985 -2390);
WIRE 16 -1 (-7000 -2400)(-7000 -2550);
WIRE 16 -1 (-7350 -2400)(-7000 -2400);
WIRE 16 -1 (-1175 -3700)(-575 -3700);
FORCEPROP 2 LAST SIG_NAME P2E_SSB_BMC_RX_C_DN
J 2
(-550 -3690);
DISPLAY 0.680851 (-550 -3690);
PAINT ORANGE (-550 -3690);
WIRE 16 -1 (-1550 -3400)(-575 -3400);
FORCEPROP 2 LAST SIG_NAME P2E_SSB_BMC_RX_C_DP
J 2
(-550 -3390);
DISPLAY 0.680851 (-550 -3390);
PAINT ORANGE (-550 -3390);
WIRE 16 -1 (-7550 -2400)(-7950 -2400);
FORCEPROP 2 LAST SIG_NAME FM_BMC_ONCTL_N
J 0
(-7935 -2390);
DISPLAY 0.680851 (-7935 -2390);
PAINT ORANGE (-7935 -2390);
WIRE 16 -1 (-7000 -575)(-7000 -650);
WIRE 16 -1 (-7000 -650)(-6450 -650);
FORCEPROP 2 LAST SIG_NAME PU_24M_OSC_OE
J 0
(-6810 -690);
DISPLAY 0.617021 (-6810 -690);
PAINT ORANGE (-6810 -690);
FORCEPROP 2 LASTPROP $XRERR UNIQUE?
J 0
(-7050 -690);
DISPLAY 0.638298 (-7050 -690);
PAINT MONO (-7050 -690);
DISPLAY INVISIBLE (-7050 -690);
WIRE 16 -1 (-5650 -550)(-4850 -550);
FORCEPROP 2 LAST SIG_NAME CLK_24M_BMC_CLKIN_R
J 0
(-5560 -540);
DISPLAY 0.617021 (-5560 -540);
PAINT ORANGE (-5560 -540);
FORCEPROP 2 LASTPROP $XRERR UNIQUE?
J 0
(-5800 -540);
DISPLAY 0.638298 (-5800 -540);
PAINT MONO (-5800 -540);
DISPLAY INVISIBLE (-5800 -540);
WIRE 16 -1 (-5350 -250)(-4850 -250);
FORCEPROP 2 LAST SIG_NAME CLK_25M_BMC
J 0
(-5285 -240);
DISPLAY 0.617021 (-5285 -240);
PAINT ORANGE (-5285 -240);
WIRE 16 -1 (-4650 -550)(-4350 -550);
FORCEPROP 2 LAST SIG_NAME CLK_24M_25M_BMC_CLKIN
J 0
(-4135 -540);
DISPLAY 0.617021 (-4135 -540);
PAINT ORANGE (-4135 -540);
WIRE 16 -1 (-4350 -550)(-3600 -550);
WIRE 16 -1 (-4350 -250)(-4350 -550);
WIRE 16 -1 (-4650 -250)(-4350 -250);
WIRE 16 3135 (-4950 -725)(-4225 -725);
WIRE 16 3135 (-4950 -100)(-4950 -725);
WIRE 16 3135 (-4225 -725)(-4225 -325);
WIRE 16 3135 (-4225 -325)(-3125 -325);
WIRE 16 3135 (-3125 -100)(-4950 -100);
WIRE 16 3135 (-3125 -325)(-3125 -100);
DOT 1 (-7000 -2400);
DOT 1 (-6200 -3750);
DOT 1 (-5950 -3700);
DOT 1 (-5700 -3600);
DOT 1 (-5200 -3450);
DOT 1 (-5450 -3550);
DOT 1 (-7475 -3250);
DOT 1 (-7500 -300);
DOT 1 (-7000 -300);
DOT 1 (-4350 -550);
FORCENOTE
BOM_COST=SM_CONTROLLER
(-7875 -4775) 0;
DISPLAY LEFT (-7875 -4775);
DISPLAY 1.595745 (-7875 -4775);
PAINT PURPLE (-7875 -4775);
FORCENOTE
CONNECT?
(-6675 -2325) 0;
DISPLAY LEFT (-6675 -2325);
DISPLAY 1.021277 (-6675 -2325);
PAINT PURPLE (-6675 -2325);
FORCENOTE
CONNECT?
(-6700 -1900) 0;
DISPLAY LEFT (-6700 -1900);
DISPLAY 1.021277 (-6700 -1900);
PAINT PURPLE (-6700 -1900);
FORCENOTE
ROOM=BMC
(-7875 -4675) 0;
DISPLAY LEFT (-7875 -4675);
DISPLAY 1.595745 (-7875 -4675);
PAINT PURPLE (-7875 -4675);
FORCENOTE
ROOM=SM_CONTROLLER
(-7858 -4852) 0;
DISPLAY LEFT (-7858 -4852);
DISPLAY 0.617021 (-7858 -4852);
PAINT PURPLE (-7858 -4852);
QUIT
